# Altium SchDoc records: 08-USBUart_DipSelects.SchDoc
|HEADER=Protel for Windows - Schematic Capture Binary File Version 5.0|Weight=2215|MinorVersion=6
|RECORD=31|FontIdCount=3|Size1=10|FontName1=Times New Roman|Size2=10|Rotation2=90|FontName2=Times New Roman|Size3=10|Underline3=T|FontName3=Times New Roman|UseMBCS=T|IsBOC=T|HotSpotGridOn=T|HotSpotGridSize=4|SheetStyle=6|SystemFont=1|BorderOn=T|TitleBlockOn=T|SheetNumberSpaceSize=12|AreaColor=16317695|SnapGridOn=T|SnapGridSize=10|VisibleGridOn=T|VisibleGridSize=10|CustomX=1500|CustomY=950|CustomXZones=6|CustomYZones=4|CustomMarginWidth=20|Display_Unit=0
|RECORD=41|OwnerPartId=-1|Color=8388608|FontID=1|IsHidden=T|Text=*|Name=CurrentTime|ReadOnlyState=1
|RECORD=41|IndexInSheet=1|OwnerPartId=-1|Color=8388608|FontID=1|IsHidden=T|Text=*|Name=CurrentDate|ReadOnlyState=1
|RECORD=41|IndexInSheet=2|OwnerPartId=-1|Color=8388608|FontID=1|IsHidden=T|Text=*|Name=Time|ReadOnlyState=1
|RECORD=41|IndexInSheet=3|OwnerPartId=-1|Color=8388608|FontID=1|IsHidden=T|Text=*|Name=Date|ReadOnlyState=1
|RECORD=41|IndexInSheet=4|OwnerPartId=-1|Color=8388608|FontID=1|IsHidden=T|Text=*|Name=DocumentFullPathAndName|ReadOnlyState=1
|RECORD=41|IndexInSheet=5|OwnerPartId=-1|Color=8388608|FontID=1|IsHidden=T|Text=*|Name=DocumentName|ReadOnlyState=1
|RECORD=41|IndexInSheet=6|OwnerPartId=-1|Color=8388608|FontID=1|IsHidden=T|Text=*|Name=ModifiedDate|ReadOnlyState=1
|RECORD=41|IndexInSheet=7|OwnerPartId=-1|Color=8388608|FontID=1|IsHidden=T|Text=*|Name=ApprovedBy|ReadOnlyState=1
|RECORD=41|IndexInSheet=8|OwnerPartId=-1|Color=8388608|FontID=1|IsHidden=T|Text=*|Name=CheckedBy|ReadOnlyState=1
|RECORD=41|IndexInSheet=9|OwnerPartId=-1|Color=8388608|FontID=1|IsHidden=T|Text=*|Name=Author|ReadOnlyState=1
|RECORD=41|IndexInSheet=10|OwnerPartId=-1|Color=8388608|FontID=1|IsHidden=T|Text=*|Name=CompanyName|ReadOnlyState=1
|RECORD=41|IndexInSheet=11|OwnerPartId=-1|Color=8388608|FontID=1|IsHidden=T|Text=*|Name=DrawnBy|ReadOnlyState=1
|RECORD=41|IndexInSheet=12|OwnerPartId=-1|Color=8388608|FontID=1|IsHidden=T|Text=*|Name=Engineer|ReadOnlyState=1
|RECORD=41|IndexInSheet=13|OwnerPartId=-1|Color=8388608|FontID=1|IsHidden=T|Text=*|Name=Organization|ReadOnlyState=1
|RECORD=41|IndexInSheet=14|OwnerPartId=-1|Color=8388608|FontID=1|IsHidden=T|Text=*|Name=Address1|ReadOnlyState=1
|RECORD=41|IndexInSheet=15|OwnerPartId=-1|Color=8388608|FontID=1|IsHidden=T|Text=*|Name=Address2|ReadOnlyState=1
|RECORD=41|IndexInSheet=16|OwnerPartId=-1|Color=8388608|FontID=1|IsHidden=T|Text=*|Name=Address3|ReadOnlyState=1
|RECORD=41|IndexInSheet=17|OwnerPartId=-1|Color=8388608|FontID=1|IsHidden=T|Text=*|Name=Address4|ReadOnlyState=1
|RECORD=41|IndexInSheet=18|OwnerPartId=-1|Color=8388608|FontID=1|IsHidden=T|Text=*|Name=Title|ReadOnlyState=1
|RECORD=41|IndexInSheet=19|OwnerPartId=-1|Color=8388608|FontID=1|IsHidden=T|Text=*|Name=DocumentNumber|ReadOnlyState=1
|RECORD=41|IndexInSheet=20|OwnerPartId=-1|Color=8388608|FontID=1|IsHidden=T|Text=*|Name=Revision|ReadOnlyState=1
|RECORD=41|IndexInSheet=21|OwnerPartId=-1|Color=8388608|FontID=1|IsHidden=T|Text=*|Name=SheetNumber|ReadOnlyState=1
|RECORD=41|IndexInSheet=22|OwnerPartId=-1|Color=8388608|FontID=1|IsHidden=T|Text=*|Name=SheetTotal|ReadOnlyState=1
|RECORD=41|IndexInSheet=23|OwnerPartId=-1|Color=8388608|FontID=1|IsHidden=T|Text=*|Name=Rule|ReadOnlyState=1
|RECORD=41|IndexInSheet=24|OwnerPartId=-1|Color=8388608|FontID=1|IsHidden=T|Text=*|Name=ImagePath|ReadOnlyState=1
|RECORD=41|IndexInSheet=25|OwnerPartId=-1|Color=8388608|FontID=1|IsHidden=T|Text=*|Name=ProjectName|ReadOnlyState=1
|RECORD=41|IndexInSheet=26|OwnerPartId=-1|Color=8388608|FontID=1|IsHidden=T|Text=*|Name=Application_BuildNumber|ReadOnlyState=1
|RECORD=1|LibReference=4bef3367ed9f9051bcb84ab46edda1c|ComponentDescription=IC USB SERIAL BASIC UART 12DFN|PartCount=2|DisplayModeCount=1|IndexInSheet=27|OwnerPartId=-1|Location.X=570|Location.Y=850|CurrentPartId=1|LibraryPath=*|SourceLibraryName=Altium Content Vault|TargetFileName=*|AreaColor=11599871|Color=128|PartIDLocked=T|DesignItemId=CMP-0248-00027-3|AllPinCount=13
|RECORD=14|OwnerIndex=28|IsNotAccesible=T|OwnerPartId=1|Location.X=590|Location.Y=760|Corner.X=720|Corner.Y=860|LineWidth=1|Color=128|AreaColor=11599871|IsSolid=T
|RECORD=2|OwnerIndex=28|OwnerPartId=1|Electrical=7|PinConglomerate=58|PinLength=20|Location.X=590|Location.Y=770|Name=3V3OUT|Designator=3|PinPropagationDelay=0.000000E+000
|RECORD=2|OwnerIndex=28|OwnerPartId=1|Electrical=7|PinConglomerate=58|PinLength=20|Location.X=590|Location.Y=850|Name=VCC|Designator=4|PinPropagationDelay=0.000000E+000
|RECORD=2|OwnerIndex=28|OwnerPartId=1|Electrical=7|PinConglomerate=58|PinLength=20|Location.X=590|Location.Y=840|Name=VCCIO|Designator=9|PinPropagationDelay=0.000000E+000
|RECORD=2|OwnerIndex=28|OwnerPartId=1|PinConglomerate=56|PinLength=20|Location.X=720|Location.Y=820|Name=C\T\S\|Designator=11|PinPropagationDelay=0.000000E+000
|RECORD=2|OwnerIndex=28|OwnerPartId=1|PinConglomerate=58|PinLength=20|Location.X=590|Location.Y=790|Name=R\E\S\E\T\|Designator=2|PinPropagationDelay=0.000000E+000
|RECORD=2|OwnerIndex=28|OwnerPartId=1|PinConglomerate=56|PinLength=20|Location.X=720|Location.Y=830|Name=R\T\S\|Designator=8|PinPropagationDelay=0.000000E+000
|RECORD=2|OwnerIndex=28|OwnerPartId=1|Electrical=1|PinConglomerate=56|PinLength=20|Location.X=720|Location.Y=800|Name=CBUS0|Designator=6|PinPropagationDelay=0.000000E+000
|RECORD=2|OwnerIndex=28|OwnerPartId=1|Electrical=2|PinConglomerate=56|PinLength=20|Location.X=720|Location.Y=840|Name=RXD|Designator=10|PinPropagationDelay=0.000000E+000
|RECORD=2|OwnerIndex=28|OwnerPartId=1|Electrical=2|PinConglomerate=56|PinLength=20|Location.X=720|Location.Y=850|Name=TXD|Designator=7|PinPropagationDelay=0.000000E+000
|RECORD=2|OwnerIndex=28|OwnerPartId=1|Electrical=1|PinConglomerate=58|PinLength=20|Location.X=590|Location.Y=820|Name=USBDM|Designator=1|PinPropagationDelay=0.000000E+000
|RECORD=2|OwnerIndex=28|OwnerPartId=1|Electrical=1|PinConglomerate=58|PinLength=20|Location.X=590|Location.Y=810|Name=USBDP|Designator=12|PinPropagationDelay=0.000000E+000
|RECORD=2|OwnerIndex=28|OwnerPartId=1|Electrical=7|PinConglomerate=56|PinLength=20|Location.X=720|Location.Y=780|Name=GND|Designator=5|PinPropagationDelay=0.000000E+000
|RECORD=2|OwnerIndex=28|OwnerPartId=1|Electrical=7|PinConglomerate=56|PinLength=20|Location.X=720|Location.Y=770|Name=GND|Designator=13|PinPropagationDelay=0.000000E+000
|RECORD=41|OwnerIndex=28|IndexInSheet=14|OwnerPartId=-1|Location.X=568|Location.Y=860|Color=8388608|FontID=1|IsHidden=T|Text=3mm|Name=Length
|RECORD=41|OwnerIndex=28|IndexInSheet=15|OwnerPartId=-1|Location.X=568|Location.Y=860|Color=8388608|FontID=1|IsHidden=T|Text=2.97V|Name=Min Supply Voltage
|RECORD=41|OwnerIndex=28|IndexInSheet=16|OwnerPartId=-1|Location.X=568|Location.Y=860|Color=8388608|FontID=1|IsHidden=T|Text=DFN|Name=Case/Package
|RECORD=41|OwnerIndex=28|IndexInSheet=17|OwnerPartId=-1|Location.X=568|Location.Y=860|Color=8388608|FontID=1|IsHidden=T|Text=1|Name=Number of Ports
|RECORD=41|OwnerIndex=28|IndexInSheet=18|OwnerPartId=-1|Location.X=568|Location.Y=860|Color=8388608|FontID=1|IsHidden=T|Text=Surface Mount|Name=Mount
|RECORD=41|OwnerIndex=28|IndexInSheet=19|OwnerPartId=-1|Location.X=568|Location.Y=860|Color=8388608|FontID=1|IsHidden=T|Text=Tape and Reel|Name=Packaging
|RECORD=41|OwnerIndex=28|IndexInSheet=20|OwnerPartId=-1|Location.X=568|Location.Y=860|Color=8388608|FontID=1|IsHidden=T|Text=5V|Name=Operating Supply Voltage
|RECORD=41|OwnerIndex=28|IndexInSheet=21|OwnerPartId=-1|Location.X=568|Location.Y=860|Color=8388608|FontID=1|IsHidden=T|Text=85°C|Name=Max Operating Temperature
|RECORD=41|OwnerIndex=28|IndexInSheet=22|OwnerPartId=-1|Location.X=568|Location.Y=860|Color=8388608|FontID=1|IsHidden=T|Text=8mA|Name=Operating Supply Current
|RECORD=41|OwnerIndex=28|IndexInSheet=23|OwnerPartId=-1|Location.X=568|Location.Y=860|Color=8388608|FontID=1|IsHidden=T|Text=0.75mm|Name=Height
|RECORD=41|OwnerIndex=28|IndexInSheet=24|OwnerPartId=-1|Location.X=568|Location.Y=860|Color=8388608|FontID=1|IsHidden=T|Text=12|Name=Number of Pins
|RECORD=41|OwnerIndex=28|IndexInSheet=25|OwnerPartId=-1|Location.X=568|Location.Y=860|Color=8388608|FontID=1|IsHidden=T|Text=5.5V|Name=Max Supply Voltage
|RECORD=41|OwnerIndex=28|IndexInSheet=26|OwnerPartId=-1|Location.X=568|Location.Y=860|Color=8388608|FontID=1|IsHidden=T|Text=1|Name=Number of Transceivers
|RECORD=41|OwnerIndex=28|IndexInSheet=27|OwnerPartId=-1|Location.X=568|Location.Y=860|Color=8388608|FontID=1|IsHidden=T|Text=5000|Name=Package Quantity
|RECORD=41|OwnerIndex=28|IndexInSheet=28|OwnerPartId=-1|Location.X=568|Location.Y=860|Color=8388608|FontID=1|IsHidden=T|Text=3Mbps|Name=Data Rate
|RECORD=41|OwnerIndex=28|IndexInSheet=29|OwnerPartId=-1|Location.X=568|Location.Y=860|Color=8388608|FontID=1|IsHidden=T|Text=-40°C|Name=Min Operating Temperature
|RECORD=41|OwnerIndex=28|IndexInSheet=30|OwnerPartId=-1|Location.X=568|Location.Y=860|Color=8388608|FontID=1|IsHidden=T|Text=3mm|Name=Width
|RECORD=41|OwnerIndex=28|IndexInSheet=31|OwnerPartId=-1|Location.X=568|Location.Y=860|Color=8388608|FontID=1|IsHidden=T|Text=No SVHC|Name=REACH SVHC
|RECORD=41|OwnerIndex=28|IndexInSheet=32|OwnerPartId=-1|Location.X=568|Location.Y=860|Color=8388608|FontID=1|IsHidden=T|Text=UART|Name=Interface
|RECORD=41|OwnerIndex=28|IndexInSheet=33|OwnerPartId=-1|Location.X=568|Location.Y=860|Color=8388608|FontID=1|IsHidden=T|Text=Lead Free|Name=Lead Free
|RECORD=34|OwnerIndex=28|IndexInSheet=-1|OwnerPartId=-1|Location.X=590|Location.Y=860|Color=8388608|FontID=1|Text=U20|Name=Designator|ReadOnlyState=1
|RECORD=41|OwnerIndex=28|IndexInSheet=-1|OwnerPartId=1|Location.X=590|Location.Y=750|Color=8388608|FontID=1|Text=FT234XD-R|Name=Comment
|RECORD=44|OwnerIndex=28
|RECORD=45|OwnerIndex=78|IndexInSheet=-1|UseComponentLibrary=T|ModelName=FP-DFN-12-IPC_B|ModelType=PCBLIB|DatafileCount=1|ModelDatafileEntity0=FP-DFN-12-IPC_B|ModelDatafileKind0=PCBLib|IsCurrent=T|DatalinksLocked=T|DatabaseDatalinksLocked=T
|RECORD=46|OwnerIndex=79
|RECORD=48|OwnerIndex=79
|RECORD=45|OwnerIndex=78|IndexInSheet=-1|UseComponentLibrary=T|ModelName=FP-DFN-12-IPC_C|ModelType=PCBLIB|DatafileCount=1|ModelDatafileEntity0=FP-DFN-12-IPC_C|ModelDatafileKind0=PCBLib|DatalinksLocked=T|DatabaseDatalinksLocked=T
|RECORD=46|OwnerIndex=82
|RECORD=48|OwnerIndex=82
|RECORD=45|OwnerIndex=78|IndexInSheet=-1|UseComponentLibrary=T|ModelName=FP-DFN-12-IPC_A|ModelType=PCBLIB|DatafileCount=1|ModelDatafileEntity0=FP-DFN-12-IPC_A|ModelDatafileKind0=PCBLib|DatalinksLocked=T|DatabaseDatalinksLocked=T
|RECORD=46|OwnerIndex=85
|RECORD=48|OwnerIndex=85
|RECORD=45|OwnerIndex=78|IndexInSheet=-1|UseComponentLibrary=T|ModelName=FP-DFN-12-MFG|ModelType=PCBLIB|DatafileCount=1|ModelDatafileEntity0=FP-DFN-12-MFG|ModelDatafileKind0=PCBLib|DatalinksLocked=T|DatabaseDatalinksLocked=T
|RECORD=46|OwnerIndex=88
|RECORD=48|OwnerIndex=88
|RECORD=1|LibReference=5e4346ad569e92388ce1b19cfc76dad|ComponentDescription=CONN RCPT USB2.0 MICRO B SMD R/A|PartCount=2|DisplayModeCount=1|IndexInSheet=28|OwnerPartId=-1|Location.X=160|Location.Y=850|CurrentPartId=1|LibraryPath=*|SourceLibraryName=Altium Content Vault|TargetFileName=*|AreaColor=11599871|Color=128|PartIDLocked=T|DesignItemId=CMP-04767-000001-1|AllPinCount=9
|RECORD=14|OwnerIndex=91|IsNotAccesible=T|OwnerPartId=1|Location.X=90|Location.Y=660|Corner.X=140|Corner.Y=870|LineWidth=1|Color=128|AreaColor=11599871|IsSolid=T
|RECORD=8|OwnerIndex=91|IsNotAccesible=T|IndexInSheet=1|OwnerPartId=1|Location.X=115|Location.Y=850|Radius=3|SecondaryRadius=3|LineWidth=1|Color=16711680
|RECORD=13|OwnerIndex=91|IsNotAccesible=T|IndexInSheet=2|OwnerPartId=1|Location.X=118|Location.Y=850|Corner.X=140|Corner.Y=850|LineWidth=1|Color=16711680
|RECORD=8|OwnerIndex=91|IsNotAccesible=T|IndexInSheet=3|OwnerPartId=1|Location.X=115|Location.Y=830|Radius=3|SecondaryRadius=3|LineWidth=1|Color=16711680
|RECORD=13|OwnerIndex=91|IsNotAccesible=T|IndexInSheet=4|OwnerPartId=1|Location.X=118|Location.Y=830|Corner.X=140|Corner.Y=830|LineWidth=1|Color=16711680
|RECORD=8|OwnerIndex=91|IsNotAccesible=T|IndexInSheet=5|OwnerPartId=1|Location.X=115|Location.Y=810|Radius=3|SecondaryRadius=3|LineWidth=1|Color=16711680
|RECORD=13|OwnerIndex=91|IsNotAccesible=T|IndexInSheet=6|OwnerPartId=1|Location.X=118|Location.Y=810|Corner.X=140|Corner.Y=810|LineWidth=1|Color=16711680
|RECORD=8|OwnerIndex=91|IsNotAccesible=T|IndexInSheet=7|OwnerPartId=1|Location.X=115|Location.Y=790|Radius=3|SecondaryRadius=3|LineWidth=1|Color=16711680
|RECORD=13|OwnerIndex=91|IsNotAccesible=T|IndexInSheet=8|OwnerPartId=1|Location.X=118|Location.Y=790|Corner.X=140|Corner.Y=790|LineWidth=1|Color=16711680
|RECORD=8|OwnerIndex=91|IsNotAccesible=T|IndexInSheet=9|OwnerPartId=1|Location.X=115|Location.Y=770|Radius=3|SecondaryRadius=3|LineWidth=1|Color=16711680
|RECORD=13|OwnerIndex=91|IsNotAccesible=T|IndexInSheet=10|OwnerPartId=1|Location.X=118|Location.Y=770|Corner.X=140|Corner.Y=770|LineWidth=1|Color=16711680
|RECORD=8|OwnerIndex=91|IsNotAccesible=T|IndexInSheet=11|OwnerPartId=1|Location.X=115|Location.Y=740|Radius=3|SecondaryRadius=3|LineWidth=1|Color=16711680
|RECORD=13|OwnerIndex=91|IsNotAccesible=T|IndexInSheet=12|OwnerPartId=1|Location.X=118|Location.Y=740|Corner.X=140|Corner.Y=740|LineWidth=1|Color=16711680
|RECORD=8|OwnerIndex=91|IsNotAccesible=T|IndexInSheet=13|OwnerPartId=1|Location.X=115|Location.Y=720|Radius=3|SecondaryRadius=3|LineWidth=1|Color=16711680
|RECORD=13|OwnerIndex=91|IsNotAccesible=T|IndexInSheet=14|OwnerPartId=1|Location.X=118|Location.Y=720|Corner.X=140|Corner.Y=720|LineWidth=1|Color=16711680
|RECORD=8|OwnerIndex=91|IsNotAccesible=T|IndexInSheet=15|OwnerPartId=1|Location.X=115|Location.Y=700|Radius=3|SecondaryRadius=3|LineWidth=1|Color=16711680
|RECORD=13|OwnerIndex=91|IsNotAccesible=T|IndexInSheet=16|OwnerPartId=1|Location.X=118|Location.Y=700|Corner.X=140|Corner.Y=700|LineWidth=1|Color=16711680
|RECORD=8|OwnerIndex=91|IsNotAccesible=T|IndexInSheet=17|OwnerPartId=1|Location.X=115|Location.Y=680|Radius=3|SecondaryRadius=3|LineWidth=1|Color=16711680
|RECORD=13|OwnerIndex=91|IsNotAccesible=T|IndexInSheet=18|OwnerPartId=1|Location.X=118|Location.Y=680|Corner.X=140|Corner.Y=680|LineWidth=1|Color=16711680
|RECORD=4|OwnerIndex=91|IsNotAccesible=T|IndexInSheet=19|OwnerPartId=1|Location.X=133|Location.Y=862|Justification=8|Color=8388608|FontID=1|Text=VBUS
|RECORD=4|OwnerIndex=91|IsNotAccesible=T|IndexInSheet=20|OwnerPartId=1|Location.X=133|Location.Y=842|Justification=8|Color=8388608|FontID=1|Text=D-
|RECORD=4|OwnerIndex=91|IsNotAccesible=T|IndexInSheet=21|OwnerPartId=1|Location.X=133|Location.Y=822|Justification=8|Color=8388608|FontID=1|Text=D+
|RECORD=4|OwnerIndex=91|IsNotAccesible=T|IndexInSheet=22|OwnerPartId=1|Location.X=133|Location.Y=802|Justification=8|Color=8388608|FontID=1|Text=ID
|RECORD=4|OwnerIndex=91|IsNotAccesible=T|IndexInSheet=23|OwnerPartId=1|Location.X=133|Location.Y=782|Justification=8|Color=8388608|FontID=1|Text=GND
|RECORD=4|OwnerIndex=91|IsNotAccesible=T|IndexInSheet=24|OwnerPartId=1|Location.X=133|Location.Y=752|Justification=8|Color=8388608|FontID=1|Text=MNT 1
|RECORD=4|OwnerIndex=91|IsNotAccesible=T|IndexInSheet=25|OwnerPartId=1|Location.X=133|Location.Y=732|Justification=8|Color=8388608|FontID=1|Text=MNT 2
|RECORD=4|OwnerIndex=91|IsNotAccesible=T|IndexInSheet=26|OwnerPartId=1|Location.X=133|Location.Y=712|Justification=8|Color=8388608|FontID=1|Text=MNT 3
|RECORD=4|OwnerIndex=91|IsNotAccesible=T|IndexInSheet=27|OwnerPartId=1|Location.X=133|Location.Y=692|Justification=8|Color=8388608|FontID=1|Text=MNT 4
|RECORD=2|OwnerIndex=91|OwnerPartId=1|Electrical=7|PinConglomerate=48|PinLength=20|Location.X=140|Location.Y=850|Name=VBUS|Designator=1|PinPropagationDelay=0.000000E+000
|RECORD=2|OwnerIndex=91|OwnerPartId=1|Electrical=1|PinConglomerate=48|PinLength=20|Location.X=140|Location.Y=830|Name=D-|Designator=2|PinPropagationDelay=0.000000E+000
|RECORD=2|OwnerIndex=91|OwnerPartId=1|Electrical=1|PinConglomerate=48|PinLength=20|Location.X=140|Location.Y=810|Name=D+|Designator=3|PinPropagationDelay=0.000000E+000
|RECORD=2|OwnerIndex=91|OwnerPartId=1|Electrical=4|PinConglomerate=48|PinLength=20|Location.X=140|Location.Y=790|Name=ID|Designator=4|PinPropagationDelay=0.000000E+000
|RECORD=2|OwnerIndex=91|OwnerPartId=1|Electrical=7|PinConglomerate=48|PinLength=20|Location.X=140|Location.Y=770|Name=GND|Designator=5|PinPropagationDelay=0.000000E+000
|RECORD=2|OwnerIndex=91|OwnerPartId=1|Electrical=4|PinConglomerate=48|PinLength=20|Location.X=140|Location.Y=740|Name=MNT 1|Designator=6|PinPropagationDelay=0.000000E+000
|RECORD=2|OwnerIndex=91|OwnerPartId=1|Electrical=4|PinConglomerate=48|PinLength=20|Location.X=140|Location.Y=720|Name=MNT 2|Designator=7|PinPropagationDelay=0.000000E+000
|RECORD=2|OwnerIndex=91|OwnerPartId=1|Electrical=4|PinConglomerate=48|PinLength=20|Location.X=140|Location.Y=700|Name=MNT 3|Designator=8|PinPropagationDelay=0.000000E+000
|RECORD=2|OwnerIndex=91|OwnerPartId=1|Electrical=4|PinConglomerate=48|PinLength=20|Location.X=140|Location.Y=680|Name=MNT 4|Designator=9|PinPropagationDelay=0.000000E+000
|RECORD=41|OwnerIndex=91|IndexInSheet=37|OwnerPartId=-1|Location.X=90|Location.Y=870|Color=8388608|FontID=1|IsHidden=T|Text=true|Name=Shielding
|RECORD=41|OwnerIndex=91|IndexInSheet=38|OwnerPartId=-1|Location.X=90|Location.Y=870|Color=8388608|FontID=1|IsHidden=T|Text=-30°C to +85°C|Name=Temperature
|RECORD=41|OwnerIndex=91|IndexInSheet=39|OwnerPartId=-1|Location.X=90|Location.Y=870|Color=8388608|FontID=1|IsHidden=T|Text=Molex|Name=Manufacturer
|RECORD=41|OwnerIndex=91|IndexInSheet=40|OwnerPartId=-1|Location.X=90|Location.Y=870|Color=8388608|FontID=1|IsHidden=T|Text=Connectors|Name=Device Class L1
|RECORD=41|OwnerIndex=91|IndexInSheet=41|OwnerPartId=-1|Location.X=90|Location.Y=870|Color=8388608|FontID=3|IsHidden=T|Text=https://www.molex.com/pdm_docs/sd/2049261103_sd.pdf|Name=Footprint Url
|RECORD=41|OwnerIndex=91|IndexInSheet=42|OwnerPartId=-1|Location.X=90|Location.Y=870|Color=8388608|FontID=1|IsHidden=T|Text=TRUE|Name=RoHS
|RECORD=41|OwnerIndex=91|IndexInSheet=43|OwnerPartId=-1|Location.X=90|Location.Y=870|Color=8388608|FontID=3|IsHidden=T|Text=https://octopart.com/2049261103-molex-91126186|Name=Octopart
|RECORD=41|OwnerIndex=91|IndexInSheet=44|OwnerPartId=-1|Location.X=90|Location.Y=870|Color=8388608|FontID=1|IsHidden=T|Text=+85°C|Name=Temperature Range High
|RECORD=41|OwnerIndex=91|IndexInSheet=45|OwnerPartId=-1|Location.X=90|Location.Y=870|Color=8388608|FontID=1|IsHidden=T|Text=-30°C|Name=Temperature Range Low
|RECORD=41|OwnerIndex=91|IndexInSheet=46|OwnerPartId=-1|Location.X=90|Location.Y=870|Color=8388608|FontID=1|IsHidden=T|Text=3.95mm|Name=Height
|RECORD=41|OwnerIndex=91|IndexInSheet=47|OwnerPartId=-1|Location.X=90|Location.Y=870|Color=8388608|FontID=1|IsHidden=T|Text=1/1.8A|Name=Current Rating
|RECORD=41|OwnerIndex=91|IndexInSheet=48|OwnerPartId=-1|Location.X=90|Location.Y=870|Color=8388608|FontID=1|IsHidden=T|Text=30V|Name=Voltage Rating
|RECORD=41|OwnerIndex=91|IndexInSheet=49|OwnerPartId=-1|Location.X=90|Location.Y=870|Color=8388608|FontID=1|IsHidden=T|Text=USB Connectors|Name=Device Class L2
|RECORD=41|OwnerIndex=91|IndexInSheet=50|OwnerPartId=-1|Location.X=90|Location.Y=870|Color=8388608|FontID=1|IsHidden=T|Text=Gold,Nickel|Name=Contact Material
|RECORD=41|OwnerIndex=91|IndexInSheet=51|OwnerPartId=-1|Location.X=90|Location.Y=870|Color=8388608|FontID=1|IsHidden=T|Text=Right Angle|Name=Conn Orientation
|RECORD=41|OwnerIndex=91|IndexInSheet=52|OwnerPartId=-1|Location.X=90|Location.Y=870|Color=8388608|FontID=1|IsHidden=T|Text=Yes|Name=Lead Free
|RECORD=41|OwnerIndex=91|IndexInSheet=53|OwnerPartId=-1|Location.X=90|Location.Y=870|Color=8388608|FontID=1|IsHidden=T|Text=0|Name=Package
|RECORD=41|OwnerIndex=91|IndexInSheet=54|OwnerPartId=-1|Location.X=90|Location.Y=870|Color=8388608|FontID=1|IsHidden=T|Text=yes|Name=Is Female
|RECORD=41|OwnerIndex=91|IndexInSheet=55|OwnerPartId=-1|Location.X=90|Location.Y=870|Color=8388608|FontID=1|IsHidden=T|Text=On a Reel of 700, Molex Micro-USB B 2.0 Micro USB Connector Receptacle, Right Angle - 204926|Name=Mouser Description
|RECORD=41|OwnerIndex=91|IndexInSheet=56|OwnerPartId=-1|Location.X=90|Location.Y=870|Color=8388608|FontID=1|IsHidden=T|Text=Datasheet|Name=ComponentLink2Description
|RECORD=41|OwnerIndex=91|IndexInSheet=57|OwnerPartId=-1|Location.X=90|Location.Y=870|Color=8388608|FontID=3|IsHidden=T|Text=https://www.molex.com/webdocs/datasheets/pdf/en-us/2049261103_IO_CONNECTORS.pdf|Name=ComponentLink2URL
|RECORD=41|OwnerIndex=91|IndexInSheet=58|OwnerPartId=-1|Location.X=90|Location.Y=870|Color=8388608|FontID=1|IsHidden=T|Text=5|Name=Number Of Contacts
|RECORD=41|OwnerIndex=91|IndexInSheet=59|OwnerPartId=-1|Location.X=90|Location.Y=870|Color=8388608|FontID=1|IsHidden=T|Text=CONN RCPT USB2.0 MICRO B SMD R/A|Name=Digikey Description
|RECORD=41|OwnerIndex=91|IndexInSheet=60|OwnerPartId=-1|Location.X=90|Location.Y=870|Color=8388608|FontID=1|IsHidden=T|Text=unset|Name=Device Class L3
|RECORD=41|OwnerIndex=91|IndexInSheet=61|OwnerPartId=-1|Location.X=90|Location.Y=870|Color=8388608|FontID=1|IsHidden=T|Text=0.65mm|Name=Pitch
|RECORD=41|OwnerIndex=91|IndexInSheet=62|OwnerPartId=-1|Location.X=90|Location.Y=870|Color=8388608|FontID=1|IsHidden=T|Text=Conn|Name=Category
|RECORD=41|OwnerIndex=91|IndexInSheet=63|OwnerPartId=-1|Location.X=90|Location.Y=870|Color=8388608|FontID=1|IsHidden=T|Text=USB 2.0|Name=Usb Standard
|RECORD=41|OwnerIndex=91|IndexInSheet=64|OwnerPartId=-1|Location.X=90|Location.Y=870|Color=8388608|FontID=1|IsHidden=T|Text=2049261103|Name=Manufacturer Part Number
|RECORD=41|OwnerIndex=91|IndexInSheet=65|OwnerPartId=-1|Location.X=90|Location.Y=870|Color=8388608|FontID=1|IsHidden=T|Text=No|Name=Automotive
|RECORD=34|OwnerIndex=91|IndexInSheet=-1|OwnerPartId=-1|Location.X=90|Location.Y=870|Color=8388608|FontID=1|Text=J43|Name=Designator|ReadOnlyState=1
|RECORD=41|OwnerIndex=91|IndexInSheet=-1|OwnerPartId=1|Location.X=90|Location.Y=650|Color=8388608|FontID=1|Text=2049261103|Name=Comment
|RECORD=44|OwnerIndex=91
|RECORD=45|OwnerIndex=169|IndexInSheet=-1|UseComponentLibrary=T|ModelName=FP-2049261103-MFG|ModelType=PCBLIB|DatafileCount=1|ModelDatafileEntity0=FP-2049261103-MFG|ModelDatafileKind0=PCBLib|IsCurrent=T|DatalinksLocked=T|DatabaseDatalinksLocked=T
|RECORD=46|OwnerIndex=170
|RECORD=48|OwnerIndex=170
|RECORD=1|LibReference=11868f565c42a9108669ba33697ecf6|ComponentDescription=CAP CER 10000PF 50V X7R 0402|PartCount=2|DisplayModeCount=1|IndexInSheet=29|OwnerPartId=-1|Location.X=220|Location.Y=770|CurrentPartId=1|LibraryPath=*|SourceLibraryName=Altium Content Vault|TargetFileName=*|AreaColor=11599871|Color=128|PartIDLocked=T|DesignItemId=CMP-2100-03592-2|AllPinCount=2
|RECORD=2|OwnerIndex=173|OwnerPartId=1|Electrical=4|PinConglomerate=49|PinLength=7|Location.X=220|Location.Y=763|Name=1|Designator=1|PinPropagationDelay=0.000000E+000
|RECORD=2|OwnerIndex=173|OwnerPartId=1|Electrical=4|PinConglomerate=51|PinLength=6|Location.X=220|Location.Y=756|Name=2|Designator=2|PinPropagationDelay=0.000000E+000
|RECORD=13|OwnerIndex=173|IsNotAccesible=T|IndexInSheet=2|OwnerPartId=1|Location.X=230|Location.Y=763|Corner.X=210|Corner.Y=763|LineWidth=1|Color=16711680
|RECORD=13|OwnerIndex=173|IsNotAccesible=T|IndexInSheet=3|OwnerPartId=1|Location.X=230|Location.Y=757|Corner.X=210|Corner.Y=757|LineWidth=1|Color=16711680
|RECORD=13|OwnerIndex=173|IsNotAccesible=T|IndexInSheet=4|OwnerPartId=1|Location.X=220|Location.Y=763|Corner.X=220|Corner.Y=766|LineWidth=1|Color=16711680
|RECORD=13|OwnerIndex=173|IsNotAccesible=T|IndexInSheet=5|OwnerPartId=1|Location.X=220|Location.Y=756|Corner.X=220|Corner.Y=755|LineWidth=1|Color=16711680
|RECORD=41|OwnerIndex=173|IndexInSheet=6|OwnerPartId=-1|Location.X=209|Location.Y=772|Color=8388608|FontID=1|IsHidden=T|Text=Ceramic Capacitors|Name=Device Class L3
|RECORD=41|OwnerIndex=173|IndexInSheet=7|OwnerPartId=-1|Location.X=209|Location.Y=772|Color=8388608|FontID=1|IsHidden=T|Text=-55°C to +125°C|Name=Temperature
|RECORD=41|OwnerIndex=173|IndexInSheet=8|OwnerPartId=-1|Location.X=209|Location.Y=772|Color=8388608|FontID=3|IsHidden=T|Text=http://www.yageo.com/exep/pages/download/literatures/UPY-C_GEN_24.pdf|Name=Footprint Url
|RECORD=41|OwnerIndex=173|IndexInSheet=9|OwnerPartId=-1|Location.X=209|Location.Y=772|Color=8388608|FontID=1|IsHidden=T|Text=CAPC10050X50|Name=Ipc Land Pattern Name
|RECORD=41|OwnerIndex=173|IndexInSheet=10|OwnerPartId=-1|Location.X=209|Location.Y=772|Color=8388608|FontID=1|IsHidden=T|Text=Passive Components|Name=Device Class L1
|RECORD=41|OwnerIndex=173|IndexInSheet=11|OwnerPartId=-1|Location.X=209|Location.Y=772|Color=8388608|FontID=1|IsHidden=T|Text=No|Name=Automotive
|RECORD=41|OwnerIndex=173|IndexInSheet=12|OwnerPartId=-1|Location.X=209|Location.Y=772|Color=8388608|FontID=3|IsHidden=T|Text=https://octopart.com/cc0402krx7r9bb103-yageo-8376513|Name=Octopart
|RECORD=41|OwnerIndex=173|IndexInSheet=13|OwnerPartId=-1|Location.X=209|Location.Y=772|Color=8388608|FontID=1|IsHidden=T|Text=30ppm/°C|Name=Temperature Coefficient
|RECORD=41|OwnerIndex=173|IndexInSheet=14|OwnerPartId=-1|Location.X=209|Location.Y=772|Color=8388608|FontID=1|IsHidden=T|Text=CC0402KRX7R9BB103|Name=Manufacturer Part Number
|RECORD=41|OwnerIndex=173|IndexInSheet=15|OwnerPartId=-1|Location.X=209|Location.Y=772|Color=8388608|FontID=1|IsHidden=T|Text=Yes|Name=Lead Free
|RECORD=41|OwnerIndex=173|IndexInSheet=16|OwnerPartId=-1|Location.X=209|Location.Y=772|Color=8388608|FontID=1|IsHidden=T|Text=-55°C|Name=Temperature Range Low
|RECORD=41|OwnerIndex=173|IndexInSheet=17|OwnerPartId=-1|Location.X=209|Location.Y=772|Color=8388608|FontID=1|IsHidden=T|Text=0.55mm|Name=Height
|RECORD=41|OwnerIndex=173|IndexInSheet=18|OwnerPartId=-1|Location.X=209|Location.Y=772|Color=8388608|FontID=3|IsHidden=T|Text=http://www.yageo.com/documents/recent/UPY-GP_NP0_16V-to-50V_16.pdf|Name=ComponentLink2URL
|RECORD=41|OwnerIndex=173|IndexInSheet=19|OwnerPartId=-1|Location.X=209|Location.Y=772|Color=8388608|FontID=1|IsHidden=T|Text=10 nF|Name=Capacitance
|RECORD=41|OwnerIndex=173|IndexInSheet=20|OwnerPartId=-1|Location.X=209|Location.Y=772|Color=8388608|FontID=1|IsHidden=T|Text=Cap|Name=Category
|RECORD=41|OwnerIndex=173|IndexInSheet=21|OwnerPartId=-1|Location.X=209|Location.Y=772|Color=8388608|FontID=1|IsHidden=T|Text=Ceramic|Name=Material
|RECORD=41|OwnerIndex=173|IndexInSheet=22|OwnerPartId=-1|Location.X=209|Location.Y=772|Color=8388608|FontID=1|IsHidden=T|Text=YAGEO|Name=Manufacturer
|RECORD=41|OwnerIndex=173|IndexInSheet=23|OwnerPartId=-1|Location.X=209|Location.Y=772|Color=8388608|FontID=1|IsHidden=T|Text=Datasheet|Name=ComponentLink2Description
|RECORD=41|OwnerIndex=173|IndexInSheet=24|OwnerPartId=-1|Location.X=209|Location.Y=772|Color=8388608|FontID=1|IsHidden=T|Text=+125°C|Name=Temperature Range High
|RECORD=41|OwnerIndex=173|IndexInSheet=25|OwnerPartId=-1|Location.X=209|Location.Y=772|Color=8388608|FontID=1|IsHidden=T|Text=CAP CER 10000PF 50V X7R 0402|Name=Digikey Description
|RECORD=41|OwnerIndex=173|IndexInSheet=26|OwnerPartId=-1|Location.X=209|Location.Y=772|Color=8388608|FontID=1|IsHidden=T|Text=50 V|Name=Voltage Rating
|RECORD=41|OwnerIndex=173|IndexInSheet=27|OwnerPartId=-1|Location.X=209|Location.Y=772|Color=8388608|FontID=1|IsHidden=T|Text=NA|Name=Automotive Grade
|RECORD=41|OwnerIndex=173|IndexInSheet=28|OwnerPartId=-1|Location.X=209|Location.Y=772|Color=8388608|FontID=1|IsHidden=T|Text=CC0402|Name=Package
|RECORD=41|OwnerIndex=173|IndexInSheet=29|OwnerPartId=-1|Location.X=209|Location.Y=772|Color=8388608|FontID=1|IsHidden=T|Text=Capacitors|Name=Device Class L2
|RECORD=41|OwnerIndex=173|IndexInSheet=30|OwnerPartId=-1|Location.X=209|Location.Y=772|Color=8388608|FontID=1|IsHidden=T|Text=0402 10 nF 50 V ±10 % Tolerance X7R SMT Multilayer Ceramic Capacitor|Name=Mouser Description
|RECORD=41|OwnerIndex=173|IndexInSheet=31|OwnerPartId=-1|Location.X=209|Location.Y=772|Color=8388608|FontID=1|IsHidden=T|Text=0.1|Name=Tolerance
|RECORD=41|OwnerIndex=173|IndexInSheet=32|OwnerPartId=-1|Location.X=209|Location.Y=772|Color=8388608|FontID=1|IsHidden=T|Text=10 nF|Name=Value
|RECORD=41|OwnerIndex=173|IndexInSheet=33|OwnerPartId=-1|Location.X=209|Location.Y=772|Color=8388608|FontID=1|IsHidden=T|Text=TRUE|Name=RoHS
|RECORD=41|OwnerIndex=173|IndexInSheet=34|OwnerPartId=-1|Location.X=209|Location.Y=772|Color=8388608|FontID=1|IsHidden=T|Text=X7R|Name=Temperature Characteristic
|RECORD=34|OwnerIndex=173|IndexInSheet=-1|OwnerPartId=-1|Location.X=210|Location.Y=750|Orientation=1|Color=8388608|FontID=2|Text=C86|Name=Designator|ReadOnlyState=1
|RECORD=41|OwnerIndex=173|IndexInSheet=-1|OwnerPartId=1|Location.X=240|Location.Y=730|Orientation=1|Color=8388608|FontID=2|Text=10nF_50V_0402|Name=Comment
|RECORD=44|OwnerIndex=173
|RECORD=45|OwnerIndex=213|IndexInSheet=-1|UseComponentLibrary=T|ModelName=FP-CC0402-MFG|ModelType=PCBLIB|DatafileCount=1|ModelDatafileEntity0=FP-CC0402-MFG|ModelDatafileKind0=PCBLib|IsCurrent=T|DatalinksLocked=T|DatabaseDatalinksLocked=T
|RECORD=46|OwnerIndex=214
|RECORD=48|OwnerIndex=214
|RECORD=45|OwnerIndex=213|IndexInSheet=-1|UseComponentLibrary=T|ModelName=FP-CC0402-IPC_C|ModelType=PCBLIB|DatafileCount=1|ModelDatafileEntity0=FP-CC0402-IPC_C|ModelDatafileKind0=PCBLib|DatalinksLocked=T|DatabaseDatalinksLocked=T
|RECORD=46|OwnerIndex=217
|RECORD=48|OwnerIndex=217
|RECORD=45|OwnerIndex=213|IndexInSheet=-1|UseComponentLibrary=T|ModelName=FP-CC0402-IPC_B|ModelType=PCBLIB|DatafileCount=1|ModelDatafileEntity0=FP-CC0402-IPC_B|ModelDatafileKind0=PCBLib|DatalinksLocked=T|DatabaseDatalinksLocked=T
|RECORD=46|OwnerIndex=220
|RECORD=48|OwnerIndex=220
|RECORD=45|OwnerIndex=213|IndexInSheet=-1|UseComponentLibrary=T|ModelName=FP-CC0402-IPC_A|ModelType=PCBLIB|DatafileCount=1|ModelDatafileEntity0=FP-CC0402-IPC_A|ModelDatafileKind0=PCBLib|DatalinksLocked=T|DatabaseDatalinksLocked=T
|RECORD=46|OwnerIndex=223
|RECORD=48|OwnerIndex=223
|RECORD=1|LibReference=5f30dd21d616792df468990f7003faa|ComponentDescription=Chip Ferrite Bead, 0603, 600O @ 100MHz, 0.15O, 25%, 1.3A|PartCount=2|DisplayModeCount=1|IndexInSheet=30|OwnerPartId=-1|Location.X=250|Location.Y=850|CurrentPartId=1|LibraryPath=*|SourceLibraryName=Altium Content Vault|TargetFileName=*|AreaColor=11599871|Color=128|PartIDLocked=T|DesignItemId=CMP-0686-00581-3|AllPinCount=2
|RECORD=2|OwnerIndex=226|OwnerPartId=1|Electrical=4|PinConglomerate=50|PinLength=20|Location.X=270|Location.Y=850|Name=1|Designator=1|PinPropagationDelay=0.000000E+000
|RECORD=2|OwnerIndex=226|OwnerPartId=1|Electrical=4|PinConglomerate=48|PinLength=20|Location.X=280|Location.Y=850|Name=2|Designator=2|PinPropagationDelay=0.000000E+000
|RECORD=13|OwnerIndex=226|IsNotAccesible=T|IndexInSheet=2|OwnerPartId=1|Location.X=267|Location.Y=847|Corner.X=278|Corner.Y=858|LineWidth=1|Color=16711680
|RECORD=13|OwnerIndex=226|IsNotAccesible=T|IndexInSheet=3|OwnerPartId=1|Location.X=272|Location.Y=842|Corner.X=283|Corner.Y=853|LineWidth=1|Color=16711680
|RECORD=13|OwnerIndex=226|IsNotAccesible=T|IndexInSheet=4|OwnerPartId=1|Location.X=278|Location.Y=858|Corner.X=283|Corner.Y=853|LineWidth=1|Color=16711680
|RECORD=13|OwnerIndex=226|IsNotAccesible=T|IndexInSheet=5|OwnerPartId=1|Location.X=272|Location.Y=842|Corner.X=267|Corner.Y=847|LineWidth=1|Color=16711680
|RECORD=13|OwnerIndex=226|IsNotAccesible=T|IndexInSheet=6|OwnerPartId=1|Location.X=270|Location.Y=850|Corner.X=267|Corner.Y=850|LineWidth=1|Color=16711680
|RECORD=13|OwnerIndex=226|IsNotAccesible=T|IndexInSheet=7|OwnerPartId=1|Location.X=280|Location.Y=850|Corner.X=283|Corner.Y=850|LineWidth=1|Color=16711680
|RECORD=41|OwnerIndex=226|IndexInSheet=8|OwnerPartId=-1|Location.X=248|Location.Y=859|Color=8388608|FontID=1|IsHidden=T|Text=Steel|Name=Material
|RECORD=41|OwnerIndex=226|IndexInSheet=9|OwnerPartId=-1|Location.X=248|Location.Y=859|Color=8388608|FontID=1|IsHidden=T|Text=25%|Name=Tolerance
|RECORD=41|OwnerIndex=226|IndexInSheet=10|OwnerPartId=-1|Location.X=248|Location.Y=859|Color=8388608|FontID=1|IsHidden=T|Text=1608|Name=Case Code (Metric)
|RECORD=41|OwnerIndex=226|IndexInSheet=11|OwnerPartId=-1|Location.X=248|Location.Y=859|Color=8388608|FontID=1|IsHidden=T|Text=0.8mm|Name=Width
|RECORD=41|OwnerIndex=226|IndexInSheet=12|OwnerPartId=-1|Location.X=248|Location.Y=859|Color=8388608|FontID=1|IsHidden=T|Text=1.3A|Name=DC Current
|RECORD=41|OwnerIndex=226|IndexInSheet=13|OwnerPartId=-1|Location.X=248|Location.Y=859|Color=8388608|FontID=1|IsHidden=T|Text=1.3A|Name=Max DC Current
|RECORD=41|OwnerIndex=226|IndexInSheet=14|OwnerPartId=-1|Location.X=248|Location.Y=859|Color=8388608|FontID=1|IsHidden=T|Text=1|Name=Package Quantity
|RECORD=41|OwnerIndex=226|IndexInSheet=15|OwnerPartId=-1|Location.X=248|Location.Y=859|Color=8388608|FontID=1|IsHidden=T|Text=1|Name=Number of Lines
|RECORD=41|OwnerIndex=226|IndexInSheet=16|OwnerPartId=-1|Location.X=248|Location.Y=859|Color=8388608|FontID=1|IsHidden=T|Text=2|Name=Number of Pins
|RECORD=41|OwnerIndex=226|IndexInSheet=17|OwnerPartId=-1|Location.X=248|Location.Y=859|Color=8388608|FontID=1|IsHidden=T|Text=Not|Name=Military Standard
|RECORD=41|OwnerIndex=226|IndexInSheet=18|OwnerPartId=-1|Location.X=248|Location.Y=859|Color=8388608|FontID=1|IsHidden=T|Text=Yes|Name=RoHS Compliant
|RECORD=41|OwnerIndex=226|IndexInSheet=19|OwnerPartId=-1|Location.X=248|Location.Y=859|Color=8388608|FontID=1|IsHidden=T|Text=SMD/SMT|Name=Termination
|RECORD=41|OwnerIndex=226|IndexInSheet=20|OwnerPartId=-1|Location.X=248|Location.Y=859|Color=8388608|FontID=1|IsHidden=T|Text=600R|Name=Impedance
|RECORD=41|OwnerIndex=226|IndexInSheet=21|OwnerPartId=-1|Location.X=248|Location.Y=859|Color=8388608|FontID=1|IsHidden=T|Text=125°C|Name=Max Operating Temperature
|RECORD=41|OwnerIndex=226|IndexInSheet=22|OwnerPartId=-1|Location.X=248|Location.Y=859|Color=8388608|FontID=1|IsHidden=T|Text=1.6mm|Name=Length
|RECORD=41|OwnerIndex=226|IndexInSheet=23|OwnerPartId=-1|Location.X=248|Location.Y=859|Color=8388608|FontID=1|IsHidden=T|Text=0.8mm|Name=Depth
|RECORD=41|OwnerIndex=226|IndexInSheet=24|OwnerPartId=-1|Location.X=248|Location.Y=859|Color=8388608|FontID=1|IsHidden=T|Text=0603|Name=Case Code (Imperial)
|RECORD=41|OwnerIndex=226|IndexInSheet=25|OwnerPartId=-1|Location.X=248|Location.Y=859|Color=8388608|FontID=1|IsHidden=T|Text=BLM18K|Name=Series
|RECORD=41|OwnerIndex=226|IndexInSheet=26|OwnerPartId=-1|Location.X=248|Location.Y=859|Color=8388608|FontID=1|IsHidden=T|Text=FERRITE BEAD|Name=Inductor Type
|RECORD=41|OwnerIndex=226|IndexInSheet=27|OwnerPartId=-1|Location.X=248|Location.Y=859|Color=8388608|FontID=1|IsHidden=T|Text=150mR|Name=DC Resistance (DCR)
|RECORD=41|OwnerIndex=226|IndexInSheet=28|OwnerPartId=-1|Location.X=248|Location.Y=859|Color=8388608|FontID=1|IsHidden=T|Text=Ferrite|Name=Core Material
|RECORD=41|OwnerIndex=226|IndexInSheet=29|OwnerPartId=-1|Location.X=248|Location.Y=859|Color=8388608|FontID=1|IsHidden=T|Text=1|Name=Number of Circuits
|RECORD=41|OwnerIndex=226|IndexInSheet=30|OwnerPartId=-1|Location.X=248|Location.Y=859|Color=8388608|FontID=1|IsHidden=T|Text=0.8mm|Name=Height
|RECORD=41|OwnerIndex=226|IndexInSheet=31|OwnerPartId=-1|Location.X=248|Location.Y=859|Color=8388608|FontID=1|IsHidden=T|Text=0603|Name=Case/Package
|RECORD=41|OwnerIndex=226|IndexInSheet=32|OwnerPartId=-1|Location.X=248|Location.Y=859|Color=8388608|FontID=1|IsHidden=T|Text=No SVHC|Name=REACH SVHC
|RECORD=41|OwnerIndex=226|IndexInSheet=33|OwnerPartId=-1|Location.X=248|Location.Y=859|Color=8388608|FontID=1|IsHidden=T|Text=Tape and Reel|Name=Packaging
|RECORD=41|OwnerIndex=226|IndexInSheet=34|OwnerPartId=-1|Location.X=248|Location.Y=859|Color=8388608|FontID=1|IsHidden=T|Text=-55°C|Name=Min Operating Temperature
|RECORD=41|OwnerIndex=226|IndexInSheet=35|OwnerPartId=-1|Location.X=248|Location.Y=859|Color=8388608|FontID=1|IsHidden=T|Text=1.3A|Name=Max Current Rating
|RECORD=41|OwnerIndex=226|IndexInSheet=36|OwnerPartId=-1|Location.X=248|Location.Y=859|Color=8388608|FontID=1|IsHidden=T|Text=No|Name=Radiation Hardening
|RECORD=41|OwnerIndex=226|IndexInSheet=37|OwnerPartId=-1|Location.X=248|Location.Y=859|Color=8388608|FontID=1|IsHidden=T|Text=1.3A|Name=Current Rating
|RECORD=41|OwnerIndex=226|IndexInSheet=38|OwnerPartId=-1|Location.X=248|Location.Y=859|Color=8388608|FontID=1|IsHidden=T|Text=Lead Free|Name=Lead Free
|RECORD=41|OwnerIndex=226|IndexInSheet=39|OwnerPartId=-1|Location.X=248|Location.Y=859|Color=8388608|FontID=1|IsHidden=T|Text=100MHz|Name=Test Frequency
|RECORD=41|OwnerIndex=226|IndexInSheet=40|OwnerPartId=-1|Location.X=248|Location.Y=859|Color=8388608|FontID=1|IsHidden=T|Text=7.1E-05oz|Name=Weight
|RECORD=34|OwnerIndex=226|IndexInSheet=-1|OwnerPartId=-1|Location.X=266|Location.Y=859|Color=8388608|FontID=1|Text=FB1|Name=Designator|ReadOnlyState=1
|RECORD=41|OwnerIndex=226|IndexInSheet=-1|OwnerPartId=1|Location.X=266|Location.Y=831|Color=8388608|FontID=1|Text=600ohm_1.3A_0603|Name=Comment
|RECORD=44|OwnerIndex=226
|RECORD=45|OwnerIndex=272|IndexInSheet=-1|UseComponentLibrary=T|ModelName=FP-BLM18-0_15-t0_8-IPC_A|ModelType=PCBLIB|DatafileCount=1|ModelDatafileEntity0=FP-BLM18-0_15-t0_8-IPC_A|ModelDatafileKind0=PCBLib|IsCurrent=T|DatalinksLocked=T|DatabaseDatalinksLocked=T
|RECORD=46|OwnerIndex=273
|RECORD=48|OwnerIndex=273
|RECORD=45|OwnerIndex=272|IndexInSheet=-1|UseComponentLibrary=T|ModelName=FP-BLM18-0_15-t0_8-MFG|ModelType=PCBLIB|DatafileCount=1|ModelDatafileEntity0=FP-BLM18-0_15-t0_8-MFG|ModelDatafileKind0=PCBLib|DatalinksLocked=T|DatabaseDatalinksLocked=T
|RECORD=46|OwnerIndex=276
|RECORD=48|OwnerIndex=276
|RECORD=45|OwnerIndex=272|IndexInSheet=-1|UseComponentLibrary=T|ModelName=FP-BLM18-0_15-t0_8-IPC_B|ModelType=PCBLIB|DatafileCount=1|ModelDatafileEntity0=FP-BLM18-0_15-t0_8-IPC_B|ModelDatafileKind0=PCBLib|DatalinksLocked=T|DatabaseDatalinksLocked=T
|RECORD=46|OwnerIndex=279
|RECORD=48|OwnerIndex=279
|RECORD=45|OwnerIndex=272|IndexInSheet=-1|UseComponentLibrary=T|ModelName=FP-BLM18-0_15-t0_8-IPC_C|ModelType=PCBLIB|DatafileCount=1|ModelDatafileEntity0=FP-BLM18-0_15-t0_8-IPC_C|ModelDatafileKind0=PCBLib|DatalinksLocked=T|DatabaseDatalinksLocked=T
|RECORD=46|OwnerIndex=282
|RECORD=48|OwnerIndex=282
|RECORD=17|IndexInSheet=31|OwnerPartId=-1|Style=4|ShowNetName=T|Location.X=180|Location.Y=660|Orientation=3|Color=128|FontID=1|Text=GND
|RECORD=25|IndexInSheet=32|OwnerPartId=-1|Location.X=170|Location.Y=830|Color=128|FontID=1|Text=FTDI_USB_R_N
|RECORD=25|IndexInSheet=33|OwnerPartId=-1|Location.X=170|Location.Y=810|Color=128|FontID=1|Text=FTDI_USB_R_P
|RECORD=1|LibReference=b4654b650e69147ec39a6b967a45e02|ComponentDescription=General Purpose Ceramic Capacitor, 0402, 100nF, 10%, X7R, 15%, 25V|PartCount=2|DisplayModeCount=1|IndexInSheet=34|OwnerPartId=-1|Location.X=550|Location.Y=720|CurrentPartId=1|LibraryPath=*|SourceLibraryName=Altium Content Vault|TargetFileName=*|AreaColor=11599871|Color=128|PartIDLocked=T|DesignItemId=CMP-2008-02519-2|AllPinCount=2
|RECORD=2|OwnerIndex=288|OwnerPartId=1|Electrical=4|PinConglomerate=49|PinLength=7|Location.X=550|Location.Y=713|Name=1|Designator=1|PinPropagationDelay=0.000000E+000
|RECORD=2|OwnerIndex=288|OwnerPartId=1|Electrical=4|PinConglomerate=51|PinLength=6|Location.X=550|Location.Y=706|Name=2|Designator=2|PinPropagationDelay=0.000000E+000
|RECORD=13|OwnerIndex=288|IsNotAccesible=T|IndexInSheet=2|OwnerPartId=1|Location.X=560|Location.Y=713|Corner.X=540|Corner.Y=713|LineWidth=1|Color=16711680
|RECORD=13|OwnerIndex=288|IsNotAccesible=T|IndexInSheet=3|OwnerPartId=1|Location.X=560|Location.Y=707|Corner.X=540|Corner.Y=707|LineWidth=1|Color=16711680
|RECORD=13|OwnerIndex=288|IsNotAccesible=T|IndexInSheet=4|OwnerPartId=1|Location.X=550|Location.Y=713|Corner.X=550|Corner.Y=716|LineWidth=1|Color=16711680
|RECORD=13|OwnerIndex=288|IsNotAccesible=T|IndexInSheet=5|OwnerPartId=1|Location.X=550|Location.Y=706|Corner.X=550|Corner.Y=705|LineWidth=1|Color=16711680
|RECORD=41|OwnerIndex=288|IndexInSheet=6|OwnerPartId=-1|Location.X=539|Location.Y=722|Color=8388608|FontID=1|IsHidden=T|Text=1|Name=Package Quantity
|RECORD=41|OwnerIndex=288|IndexInSheet=7|OwnerPartId=-1|Location.X=539|Location.Y=722|Color=8388608|FontID=1|IsHidden=T|Text=100nF|Name=Capacitance
|RECORD=41|OwnerIndex=288|IndexInSheet=8|OwnerPartId=-1|Location.X=539|Location.Y=722|Color=8388608|FontID=1|IsHidden=T|Text=-55°C|Name=Min Operating Temperature
|RECORD=41|OwnerIndex=288|IndexInSheet=9|OwnerPartId=-1|Location.X=539|Location.Y=722|Color=8388608|FontID=1|IsHidden=T|Text=25V|Name=Voltage
|RECORD=41|OwnerIndex=288|IndexInSheet=10|OwnerPartId=-1|Location.X=539|Location.Y=722|Color=8388608|FontID=1|IsHidden=T|Text=25V|Name=Voltage Rating
|RECORD=41|OwnerIndex=288|IndexInSheet=11|OwnerPartId=-1|Location.X=539|Location.Y=722|Color=8388608|FontID=1|IsHidden=T|Text=Flat|Name=Construction
|RECORD=41|OwnerIndex=288|IndexInSheet=12|OwnerPartId=-1|Location.X=539|Location.Y=722|Color=8388608|FontID=1|IsHidden=T|Text=125°C|Name=Max Operating Temperature
|RECORD=41|OwnerIndex=288|IndexInSheet=13|OwnerPartId=-1|Location.X=539|Location.Y=722|Color=8388608|FontID=1|IsHidden=T|Text=No|Name=Radiation Hardening
|RECORD=41|OwnerIndex=288|IndexInSheet=14|OwnerPartId=-1|Location.X=539|Location.Y=722|Color=8388608|FontID=1|IsHidden=T|Text=0.5mm|Name=Depth
|RECORD=41|OwnerIndex=288|IndexInSheet=15|OwnerPartId=-1|Location.X=539|Location.Y=722|Color=8388608|FontID=1|IsHidden=T|Text=0.022inch|Name=Thickness
|RECORD=41|OwnerIndex=288|IndexInSheet=16|OwnerPartId=-1|Location.X=539|Location.Y=722|Color=8388608|FontID=1|IsHidden=T|Text=25V|Name=Voltage Rating (DC)
|RECORD=41|OwnerIndex=288|IndexInSheet=17|OwnerPartId=-1|Location.X=539|Location.Y=722|Color=8388608|FontID=1|IsHidden=T|Text=2|Name=Number of Pins
|RECORD=41|OwnerIndex=288|IndexInSheet=18|OwnerPartId=-1|Location.X=539|Location.Y=722|Color=8388608|FontID=1|IsHidden=T|Text=Lead Free|Name=Lead Free
|RECORD=41|OwnerIndex=288|IndexInSheet=19|OwnerPartId=-1|Location.X=539|Location.Y=722|Color=8388608|FontID=1|IsHidden=T|Text=-|Name=Series
|RECORD=41|OwnerIndex=288|IndexInSheet=20|OwnerPartId=-1|Location.X=539|Location.Y=722|Color=8388608|FontID=1|IsHidden=T|Text=No SVHC|Name=REACH SVHC
|RECORD=41|OwnerIndex=288|IndexInSheet=21|OwnerPartId=-1|Location.X=539|Location.Y=722|Color=8388608|FontID=1|IsHidden=T|Text=1mm|Name=Length
|RECORD=41|OwnerIndex=288|IndexInSheet=22|OwnerPartId=-1|Location.X=539|Location.Y=722|Color=8388608|FontID=1|IsHidden=T|Text=X7R|Name=Dielectric
|RECORD=41|OwnerIndex=288|IndexInSheet=23|OwnerPartId=-1|Location.X=539|Location.Y=722|Color=8388608|FontID=1|IsHidden=T|Text=Yes|Name=RoHS Compliant
|RECORD=41|OwnerIndex=288|IndexInSheet=24|OwnerPartId=-1|Location.X=539|Location.Y=722|Color=8388608|FontID=1|IsHidden=T|Text=Surface Mount|Name=Mount
|RECORD=41|OwnerIndex=288|IndexInSheet=25|OwnerPartId=-1|Location.X=539|Location.Y=722|Color=8388608|FontID=1|IsHidden=T|Text=Tape and Reel|Name=Packaging
|RECORD=41|OwnerIndex=288|IndexInSheet=26|OwnerPartId=-1|Location.X=539|Location.Y=722|Color=8388608|FontID=1|IsHidden=T|Text=0402|Name=Case/Package
|RECORD=41|OwnerIndex=288|IndexInSheet=27|OwnerPartId=-1|Location.X=539|Location.Y=722|Color=8388608|FontID=1|IsHidden=T|Text=0402|Name=Case Code (Imperial)
|RECORD=41|OwnerIndex=288|IndexInSheet=28|OwnerPartId=-1|Location.X=539|Location.Y=722|Color=8388608|FontID=1|IsHidden=T|Text=SMD/SMT|Name=Termination
|RECORD=41|OwnerIndex=288|IndexInSheet=29|OwnerPartId=-1|Location.X=539|Location.Y=722|Color=8388608|FontID=1|IsHidden=T|Text=0.02inch|Name=Width
|RECORD=41|OwnerIndex=288|IndexInSheet=30|OwnerPartId=-1|Location.X=539|Location.Y=722|Color=8388608|FontID=1|IsHidden=T|Text=1005|Name=Case Code (Metric)
|RECORD=41|OwnerIndex=288|IndexInSheet=31|OwnerPartId=-1|Location.X=539|Location.Y=722|Color=8388608|FontID=1|IsHidden=T|Text=10%|Name=Tolerance
|RECORD=34|OwnerIndex=288|IndexInSheet=-1|OwnerPartId=-1|Location.X=540|Location.Y=700|Orientation=1|Color=8388608|FontID=2|Text=C92|Name=Designator|ReadOnlyState=1
|RECORD=41|OwnerIndex=288|IndexInSheet=-1|OwnerPartId=1|Location.X=570|Location.Y=685|Orientation=1|Color=8388608|FontID=2|Text=0.1uF_25V_0402|Name=Comment
|RECORD=44|OwnerIndex=288
|RECORD=45|OwnerIndex=325|IndexInSheet=-1|UseComponentLibrary=T|ModelName=FP-0402-L_1_0_1-W_0_5_0_1-IPC_C|ModelType=PCBLIB|DatafileCount=1|ModelDatafileEntity0=FP-0402-L_1_0_1-W_0_5_0_1-IPC_C|ModelDatafileKind0=PCBLib|IsCurrent=T|DatalinksLocked=T|DatabaseDatalinksLocked=T
|RECORD=46|OwnerIndex=326
|RECORD=48|OwnerIndex=326
|RECORD=45|OwnerIndex=325|IndexInSheet=-1|UseComponentLibrary=T|ModelName=FP-0402-L_1_0_1-W_0_5_0_1-IPC_B|ModelType=PCBLIB|DatafileCount=1|ModelDatafileEntity0=FP-0402-L_1_0_1-W_0_5_0_1-IPC_B|ModelDatafileKind0=PCBLib|DatalinksLocked=T|DatabaseDatalinksLocked=T
|RECORD=46|OwnerIndex=329
|RECORD=48|OwnerIndex=329
|RECORD=45|OwnerIndex=325|IndexInSheet=-1|UseComponentLibrary=T|ModelName=FP-0402-L_1_0_1-W_0_5_0_1-MFG|ModelType=PCBLIB|DatafileCount=1|ModelDatafileEntity0=FP-0402-L_1_0_1-W_0_5_0_1-MFG|ModelDatafileKind0=PCBLib|DatalinksLocked=T|DatabaseDatalinksLocked=T
|RECORD=46|OwnerIndex=332
|RECORD=48|OwnerIndex=332
|RECORD=45|OwnerIndex=325|IndexInSheet=-1|UseComponentLibrary=T|ModelName=FP-0402-L_1_0_1-W_0_5_0_1-IPC_A|ModelType=PCBLIB|DatafileCount=1|ModelDatafileEntity0=FP-0402-L_1_0_1-W_0_5_0_1-IPC_A|ModelDatafileKind0=PCBLib|DatalinksLocked=T|DatabaseDatalinksLocked=T
|RECORD=46|OwnerIndex=335
|RECORD=48|OwnerIndex=335
|RECORD=1|LibReference=RES|PartCount=2|DisplayModeCount=2|IndexInSheet=35|OwnerPartId=-1|Location.X=430|Location.Y=820|CurrentPartId=1|SourceLibraryName=Altium Content Vault|TargetFileName=*|AreaColor=11599871|Color=128|PartIDLocked=F|DesignItemId=CMP-2002-08434-1|AllPinCount=2
|RECORD=2|OwnerIndex=338|OwnerPartId=1|OwnerPartDisplayMode=1|FormalType=1|Electrical=4|PinConglomerate=32|PinLength=10|Location.X=450|Location.Y=810|Name=2|Designator=2|PinPropagationDelay=0.000000E+000
|RECORD=2|OwnerIndex=338|OwnerPartId=1|OwnerPartDisplayMode=1|FormalType=1|Electrical=4|PinConglomerate=34|PinLength=10|Location.X=430|Location.Y=810|Name=1|Designator=1|PinPropagationDelay=0.000000E+000
|RECORD=14|OwnerIndex=338|IsNotAccesible=T|IndexInSheet=2|OwnerPartId=1|OwnerPartDisplayMode=1|Location.X=430|Location.Y=806|Corner.X=450|Corner.Y=814|LineWidth=1|Color=16711680|AreaColor=11599871
|RECORD=2|OwnerIndex=338|OwnerPartId=1|FormalType=1|Electrical=4|PinConglomerate=32|PinLength=10|Location.X=450|Location.Y=810|Name=2|Designator=2|PinPropagationDelay=0.000000E+000
|RECORD=2|OwnerIndex=338|OwnerPartId=1|FormalType=1|Electrical=4|PinConglomerate=34|PinLength=10|Location.X=430|Location.Y=810|Name=1|Designator=1|PinPropagationDelay=0.000000E+000
|RECORD=6|OwnerIndex=338|IsNotAccesible=T|IndexInSheet=5|OwnerPartId=1|LineWidth=1|Color=16711680|LocationCount=10|X1=450|Y1=810|X2=446|Y2=810|X3=445|Y3=808|X4=443|Y4=812|X5=441|Y5=808|X6=439|Y6=812|X7=437|Y7=808|X8=435|Y8=812|X9=434|Y9=810|X10=430|Y10=810
|RECORD=41|OwnerIndex=338|IndexInSheet=6|OwnerPartId=-1|Location.X=418|Location.Y=823|Color=8388608|FontID=1|IsHidden=T|Text=CRCW040227R0FKED|Name=Part Number
|RECORD=41|OwnerIndex=338|IndexInSheet=7|OwnerPartId=-1|Location.X=418|Location.Y=823|Color=8388608|FontID=1|IsHidden=T|Text=Vishay Dale|Name=Manufacturer
|RECORD=34|OwnerIndex=338|IndexInSheet=-1|OwnerPartId=-1|Location.X=410|Location.Y=810|Color=8388608|FontID=1|Text=R81|Name=Designator|ReadOnlyState=1
|RECORD=41|OwnerIndex=338|IndexInSheet=-1|OwnerPartId=-1|Location.X=430|Location.Y=810|Color=8388608|FontID=1|Text=27_1%_0402|Name=Comment
|RECORD=44|OwnerIndex=338
|RECORD=45|OwnerIndex=353|IndexInSheet=-1|Description=Chip Resistor, 2-Leads, Body 1.00x0.50mm, IPC Medium Density|UseComponentLibrary=T|ModelName=RESC1005X40X25NL05T05|ModelType=PCBLIB|DatafileCount=1|ModelDatafileEntity0=RESC1005X40X25NL05T05|ModelDatafileKind0=PCBLib|IsCurrent=T|DatalinksLocked=T|DatabaseDatalinksLocked=T
|RECORD=46|OwnerIndex=354
|RECORD=48|OwnerIndex=354
|RECORD=41|OwnerIndex=356|IndexInSheet=-1|OwnerPartId=-1|Color=8388608|FontID=1|IsHidden=T|Text=2D|Name=Available Preview Images
|RECORD=45|OwnerIndex=353|IndexInSheet=-1|Description=Chip Resistor, 2-Leads, Body 1.00x0.50mm, IPC High Density|UseComponentLibrary=T|ModelName=RESC1005X40X25LL05T05|ModelType=PCBLIB|DatafileCount=1|ModelDatafileEntity0=RESC1005X40X25LL05T05|ModelDatafileKind0=PCBLib|DatalinksLocked=T|DatabaseDatalinksLocked=T
|RECORD=46|OwnerIndex=358
|RECORD=48|OwnerIndex=358
|RECORD=41|OwnerIndex=360|IndexInSheet=-1|OwnerPartId=-1|Color=8388608|FontID=1|IsHidden=T|Text=2D|Name=Available Preview Images
|RECORD=45|OwnerIndex=353|IndexInSheet=-1|Description=Chip Resistor, 2-Leads, Body 1.00x0.50mm, IPC Low Density|UseComponentLibrary=T|ModelName=RESC1005X40X25ML05T05|ModelType=PCBLIB|DatafileCount=1|ModelDatafileEntity0=RESC1005X40X25ML05T05|ModelDatafileKind0=PCBLib|DatalinksLocked=T|DatabaseDatalinksLocked=T
|RECORD=46|OwnerIndex=362
|RECORD=48|OwnerIndex=362
|RECORD=41|OwnerIndex=364|IndexInSheet=-1|OwnerPartId=-1|Color=8388608|FontID=1|IsHidden=T|Text=2D|Name=Available Preview Images
|RECORD=1|LibReference=RES|PartCount=2|DisplayModeCount=2|IndexInSheet=36|OwnerPartId=-1|Location.X=430|Location.Y=830|CurrentPartId=1|SourceLibraryName=Altium Content Vault|TargetFileName=*|AreaColor=11599871|Color=128|PartIDLocked=F|DesignItemId=CMP-2002-08434-1|AllPinCount=2
|RECORD=2|OwnerIndex=366|OwnerPartId=1|OwnerPartDisplayMode=1|FormalType=1|Electrical=4|PinConglomerate=32|PinLength=10|Location.X=450|Location.Y=820|Name=2|Designator=2|PinPropagationDelay=0.000000E+000
|RECORD=2|OwnerIndex=366|OwnerPartId=1|OwnerPartDisplayMode=1|FormalType=1|Electrical=4|PinConglomerate=34|PinLength=10|Location.X=430|Location.Y=820|Name=1|Designator=1|PinPropagationDelay=0.000000E+000
|RECORD=14|OwnerIndex=366|IsNotAccesible=T|IndexInSheet=2|OwnerPartId=1|OwnerPartDisplayMode=1|Location.X=430|Location.Y=816|Corner.X=450|Corner.Y=824|LineWidth=1|Color=16711680|AreaColor=11599871
|RECORD=2|OwnerIndex=366|OwnerPartId=1|FormalType=1|Electrical=4|PinConglomerate=32|PinLength=10|Location.X=450|Location.Y=820|Name=2|Designator=2|PinPropagationDelay=0.000000E+000
|RECORD=2|OwnerIndex=366|OwnerPartId=1|FormalType=1|Electrical=4|PinConglomerate=34|PinLength=10|Location.X=430|Location.Y=820|Name=1|Designator=1|PinPropagationDelay=0.000000E+000
|RECORD=6|OwnerIndex=366|IsNotAccesible=T|IndexInSheet=5|OwnerPartId=1|LineWidth=1|Color=16711680|LocationCount=10|X1=450|Y1=820|X2=446|Y2=820|X3=445|Y3=818|X4=443|Y4=822|X5=441|Y5=818|X6=439|Y6=822|X7=437|Y7=818|X8=435|Y8=822|X9=434|Y9=820|X10=430|Y10=820
|RECORD=41|OwnerIndex=366|IndexInSheet=6|OwnerPartId=-1|Location.X=418|Location.Y=833|Color=8388608|FontID=1|IsHidden=T|Text=CRCW040227R0FKED|Name=Part Number
|RECORD=41|OwnerIndex=366|IndexInSheet=7|OwnerPartId=-1|Location.X=418|Location.Y=833|Color=8388608|FontID=1|IsHidden=T|Text=Vishay Dale|Name=Manufacturer
|RECORD=34|OwnerIndex=366|IndexInSheet=-1|OwnerPartId=-1|Location.X=410|Location.Y=820|Color=8388608|FontID=1|Text=R43|Name=Designator|ReadOnlyState=1
|RECORD=41|OwnerIndex=366|IndexInSheet=-1|OwnerPartId=-1|Location.X=430|Location.Y=820|Color=8388608|FontID=1|Text=27_1%_0402|Name=Comment
|RECORD=44|OwnerIndex=366
|RECORD=45|OwnerIndex=381|IndexInSheet=-1|Description=Chip Resistor, 2-Leads, Body 1.00x0.50mm, IPC Medium Density|UseComponentLibrary=T|ModelName=RESC1005X40X25NL05T05|ModelType=PCBLIB|DatafileCount=1|ModelDatafileEntity0=RESC1005X40X25NL05T05|ModelDatafileKind0=PCBLib|IsCurrent=T|DatalinksLocked=T|DatabaseDatalinksLocked=T
|RECORD=46|OwnerIndex=382
|RECORD=48|OwnerIndex=382
|RECORD=41|OwnerIndex=384|IndexInSheet=-1|OwnerPartId=-1|Color=8388608|FontID=1|IsHidden=T|Text=2D|Name=Available Preview Images
|RECORD=45|OwnerIndex=381|IndexInSheet=-1|Description=Chip Resistor, 2-Leads, Body 1.00x0.50mm, IPC High Density|UseComponentLibrary=T|ModelName=RESC1005X40X25LL05T05|ModelType=PCBLIB|DatafileCount=1|ModelDatafileEntity0=RESC1005X40X25LL05T05|ModelDatafileKind0=PCBLib|DatalinksLocked=T|DatabaseDatalinksLocked=T
|RECORD=46|OwnerIndex=386
|RECORD=48|OwnerIndex=386
|RECORD=41|OwnerIndex=388|IndexInSheet=-1|OwnerPartId=-1|Color=8388608|FontID=1|IsHidden=T|Text=2D|Name=Available Preview Images
|RECORD=45|OwnerIndex=381|IndexInSheet=-1|Description=Chip Resistor, 2-Leads, Body 1.00x0.50mm, IPC Low Density|UseComponentLibrary=T|ModelName=RESC1005X40X25ML05T05|ModelType=PCBLIB|DatafileCount=1|ModelDatafileEntity0=RESC1005X40X25ML05T05|ModelDatafileKind0=PCBLib|DatalinksLocked=T|DatabaseDatalinksLocked=T
|RECORD=46|OwnerIndex=390
|RECORD=48|OwnerIndex=390
|RECORD=41|OwnerIndex=392|IndexInSheet=-1|OwnerPartId=-1|Color=8388608|FontID=1|IsHidden=T|Text=2D|Name=Available Preview Images
|RECORD=25|IndexInSheet=37|OwnerPartId=-1|Location.X=490|Location.Y=820|Color=128|FontID=1|Text=FTDI_USB_N
|RECORD=25|IndexInSheet=38|OwnerPartId=-1|Location.X=490|Location.Y=810|Color=128|FontID=1|Text=FTDI_USB_P
|RECORD=25|IndexInSheet=39|OwnerPartId=-1|Location.X=340|Location.Y=850|Color=128|FontID=1|Text=FTDI_VBUS
|RECORD=25|IndexInSheet=40|OwnerPartId=-1|Location.X=170|Location.Y=850|Color=128|FontID=1|Text=USB_VBUS
|RECORD=17|IndexInSheet=41|OwnerPartId=-1|Style=4|ShowNetName=T|Location.X=550|Location.Y=660|Orientation=3|Color=128|FontID=1|Text=GND
|RECORD=17|IndexInSheet=42|OwnerPartId=-1|Style=4|ShowNetName=T|Location.X=750|Location.Y=750|Orientation=3|Color=128|FontID=1|Text=GND
|RECORD=1|LibReference=RES|PartCount=2|DisplayModeCount=2|IndexInSheet=43|OwnerPartId=-1|Location.X=450|Location.Y=780|Orientation=2|CurrentPartId=1|SourceLibraryName=Altium Content Vault|TargetFileName=*|AreaColor=11599871|Color=128|PartIDLocked=F|DesignItemId=CMP-2002-07353-1|AllPinCount=2
|RECORD=2|OwnerIndex=400|OwnerPartId=1|OwnerPartDisplayMode=1|FormalType=1|Electrical=4|PinConglomerate=34|PinLength=10|Location.X=430|Location.Y=790|Name=2|Designator=2|PinPropagationDelay=0.000000E+000
|RECORD=2|OwnerIndex=400|OwnerPartId=1|OwnerPartDisplayMode=1|FormalType=1|Electrical=4|PinConglomerate=32|PinLength=10|Location.X=450|Location.Y=790|Name=1|Designator=1|PinPropagationDelay=0.000000E+000
|RECORD=14|OwnerIndex=400|IsNotAccesible=T|IndexInSheet=2|OwnerPartId=1|OwnerPartDisplayMode=1|Location.X=430|Location.Y=786|Corner.X=450|Corner.Y=794|LineWidth=1|Color=16711680|AreaColor=11599871
|RECORD=2|OwnerIndex=400|OwnerPartId=1|FormalType=1|Electrical=4|PinConglomerate=34|PinLength=10|Location.X=430|Location.Y=790|Name=2|Designator=2|PinPropagationDelay=0.000000E+000
|RECORD=2|OwnerIndex=400|OwnerPartId=1|FormalType=1|Electrical=4|PinConglomerate=32|PinLength=10|Location.X=450|Location.Y=790|Name=1|Designator=1|PinPropagationDelay=0.000000E+000
|RECORD=6|OwnerIndex=400|IsNotAccesible=T|IndexInSheet=5|OwnerPartId=1|LineWidth=1|Color=16711680|LocationCount=10|X1=430|Y1=790|X2=434|Y2=790|X3=435|Y3=792|X4=437|Y4=788|X5=439|Y5=792|X6=441|Y6=788|X7=443|Y7=792|X8=445|Y8=788|X9=446|Y9=790|X10=450|Y10=790
|RECORD=41|OwnerIndex=400|IndexInSheet=6|OwnerPartId=-1|Location.X=418|Location.Y=793|Color=8388608|FontID=1|IsHidden=T|Text=RC0402FR-0710KL|Name=Part Number
|RECORD=41|OwnerIndex=400|IndexInSheet=7|OwnerPartId=-1|Location.X=418|Location.Y=793|Color=8388608|FontID=1|IsHidden=T|Text=Yageo / Phycomp|Name=Manufacturer
|RECORD=34|OwnerIndex=400|IndexInSheet=-1|OwnerPartId=-1|Location.X=429|Location.Y=793|Color=8388608|FontID=1|Text=R82|Name=Designator|ReadOnlyState=1
|RECORD=41|OwnerIndex=400|IndexInSheet=-1|OwnerPartId=-1|Location.X=429|Location.Y=777|Color=8388608|FontID=1|Text=10K_1%_0402|Name=Comment
|RECORD=44|OwnerIndex=400
|RECORD=45|OwnerIndex=415|IndexInSheet=-1|Description=Chip Resistor, 2-Leads, Body 1.00x0.50mm, IPC High Density|UseComponentLibrary=T|ModelName=RESC1005X40X25LL05T10|ModelType=PCBLIB|DatafileCount=1|ModelDatafileEntity0=RESC1005X40X25LL05T10|ModelDatafileKind0=PCBLib|IsCurrent=T|DatalinksLocked=T|DatabaseDatalinksLocked=T
|RECORD=46|OwnerIndex=416
|RECORD=48|OwnerIndex=416
|RECORD=41|OwnerIndex=418|IndexInSheet=-1|OwnerPartId=-1|Color=8388608|FontID=1|IsHidden=T|Text=2D|Name=Available Preview Images
|RECORD=45|OwnerIndex=415|IndexInSheet=-1|Description=Chip Resistor, 2-Leads, Body 1.00x0.50mm, IPC Low Density|UseComponentLibrary=T|ModelName=RESC1005X40X25ML05T10|ModelType=PCBLIB|DatafileCount=1|ModelDatafileEntity0=RESC1005X40X25ML05T10|ModelDatafileKind0=PCBLib|DatalinksLocked=T|DatabaseDatalinksLocked=T
|RECORD=46|OwnerIndex=420
|RECORD=48|OwnerIndex=420
|RECORD=41|OwnerIndex=422|IndexInSheet=-1|OwnerPartId=-1|Color=8388608|FontID=1|IsHidden=T|Text=2D|Name=Available Preview Images
|RECORD=45|OwnerIndex=415|IndexInSheet=-1|Description=Chip Resistor, 2-Leads, Body 1.00x0.50mm, IPC Medium Density|UseComponentLibrary=T|ModelName=RESC1005X40X25NL05T10|ModelType=PCBLIB|DatafileCount=1|ModelDatafileEntity0=RESC1005X40X25NL05T10|ModelDatafileKind0=PCBLib|DatalinksLocked=T|DatabaseDatalinksLocked=T
|RECORD=46|OwnerIndex=424
|RECORD=48|OwnerIndex=424
|RECORD=41|OwnerIndex=426|IndexInSheet=-1|OwnerPartId=-1|Color=8388608|FontID=1|IsHidden=T|Text=2D|Name=Available Preview Images
|RECORD=17|IndexInSheet=44|OwnerPartId=-1|Style=4|ShowNetName=T|Location.X=490|Location.Y=660|Orientation=3|Color=128|FontID=1|Text=GND
|RECORD=1|LibReference=11868f565c42a9108669ba33697ecf6|ComponentDescription=CAP CER 10000PF 50V X7R 0402|PartCount=2|DisplayModeCount=1|IndexInSheet=45|OwnerPartId=-1|Location.X=450|Location.Y=740|CurrentPartId=1|LibraryPath=*|SourceLibraryName=Altium Content Vault|TargetFileName=*|AreaColor=11599871|Color=128|PartIDLocked=T|DesignItemId=CMP-2100-03592-2|AllPinCount=2
|RECORD=2|OwnerIndex=429|OwnerPartId=1|Electrical=4|PinConglomerate=49|PinLength=7|Location.X=450|Location.Y=733|Name=1|Designator=1|PinPropagationDelay=0.000000E+000
|RECORD=2|OwnerIndex=429|OwnerPartId=1|Electrical=4|PinConglomerate=51|PinLength=6|Location.X=450|Location.Y=726|Name=2|Designator=2|PinPropagationDelay=0.000000E+000
|RECORD=13|OwnerIndex=429|IsNotAccesible=T|IndexInSheet=2|OwnerPartId=1|Location.X=460|Location.Y=733|Corner.X=440|Corner.Y=733|LineWidth=1|Color=16711680
|RECORD=13|OwnerIndex=429|IsNotAccesible=T|IndexInSheet=3|OwnerPartId=1|Location.X=460|Location.Y=727|Corner.X=440|Corner.Y=727|LineWidth=1|Color=16711680
|RECORD=13|OwnerIndex=429|IsNotAccesible=T|IndexInSheet=4|OwnerPartId=1|Location.X=450|Location.Y=733|Corner.X=450|Corner.Y=736|LineWidth=1|Color=16711680
|RECORD=13|OwnerIndex=429|IsNotAccesible=T|IndexInSheet=5|OwnerPartId=1|Location.X=450|Location.Y=726|Corner.X=450|Corner.Y=725|LineWidth=1|Color=16711680
|RECORD=41|OwnerIndex=429|IndexInSheet=6|OwnerPartId=-1|Location.X=439|Location.Y=742|Color=8388608|FontID=1|IsHidden=T|Text=Ceramic Capacitors|Name=Device Class L3
|RECORD=41|OwnerIndex=429|IndexInSheet=7|OwnerPartId=-1|Location.X=439|Location.Y=742|Color=8388608|FontID=1|IsHidden=T|Text=-55°C to +125°C|Name=Temperature
|RECORD=41|OwnerIndex=429|IndexInSheet=8|OwnerPartId=-1|Location.X=439|Location.Y=742|Color=8388608|FontID=3|IsHidden=T|Text=http://www.yageo.com/exep/pages/download/literatures/UPY-C_GEN_24.pdf|Name=Footprint Url
|RECORD=41|OwnerIndex=429|IndexInSheet=9|OwnerPartId=-1|Location.X=439|Location.Y=742|Color=8388608|FontID=1|IsHidden=T|Text=CAPC10050X50|Name=Ipc Land Pattern Name
|RECORD=41|OwnerIndex=429|IndexInSheet=10|OwnerPartId=-1|Location.X=439|Location.Y=742|Color=8388608|FontID=1|IsHidden=T|Text=Passive Components|Name=Device Class L1
|RECORD=41|OwnerIndex=429|IndexInSheet=11|OwnerPartId=-1|Location.X=439|Location.Y=742|Color=8388608|FontID=1|IsHidden=T|Text=No|Name=Automotive
|RECORD=41|OwnerIndex=429|IndexInSheet=12|OwnerPartId=-1|Location.X=439|Location.Y=742|Color=8388608|FontID=3|IsHidden=T|Text=https://octopart.com/cc0402krx7r9bb103-yageo-8376513|Name=Octopart
|RECORD=41|OwnerIndex=429|IndexInSheet=13|OwnerPartId=-1|Location.X=439|Location.Y=742|Color=8388608|FontID=1|IsHidden=T|Text=30ppm/°C|Name=Temperature Coefficient
|RECORD=41|OwnerIndex=429|IndexInSheet=14|OwnerPartId=-1|Location.X=439|Location.Y=742|Color=8388608|FontID=1|IsHidden=T|Text=CC0402KRX7R9BB103|Name=Manufacturer Part Number
|RECORD=41|OwnerIndex=429|IndexInSheet=15|OwnerPartId=-1|Location.X=439|Location.Y=742|Color=8388608|FontID=1|IsHidden=T|Text=Yes|Name=Lead Free
|RECORD=41|OwnerIndex=429|IndexInSheet=16|OwnerPartId=-1|Location.X=439|Location.Y=742|Color=8388608|FontID=1|IsHidden=T|Text=-55°C|Name=Temperature Range Low
|RECORD=41|OwnerIndex=429|IndexInSheet=17|OwnerPartId=-1|Location.X=439|Location.Y=742|Color=8388608|FontID=1|IsHidden=T|Text=0.55mm|Name=Height
|RECORD=41|OwnerIndex=429|IndexInSheet=18|OwnerPartId=-1|Location.X=439|Location.Y=742|Color=8388608|FontID=3|IsHidden=T|Text=http://www.yageo.com/documents/recent/UPY-GP_NP0_16V-to-50V_16.pdf|Name=ComponentLink2URL
|RECORD=41|OwnerIndex=429|IndexInSheet=19|OwnerPartId=-1|Location.X=439|Location.Y=742|Color=8388608|FontID=1|IsHidden=T|Text=10 nF|Name=Capacitance
|RECORD=41|OwnerIndex=429|IndexInSheet=20|OwnerPartId=-1|Location.X=439|Location.Y=742|Color=8388608|FontID=1|IsHidden=T|Text=Cap|Name=Category
|RECORD=41|OwnerIndex=429|IndexInSheet=21|OwnerPartId=-1|Location.X=439|Location.Y=742|Color=8388608|FontID=1|IsHidden=T|Text=Ceramic|Name=Material
|RECORD=41|OwnerIndex=429|IndexInSheet=22|OwnerPartId=-1|Location.X=439|Location.Y=742|Color=8388608|FontID=1|IsHidden=T|Text=YAGEO|Name=Manufacturer
|RECORD=41|OwnerIndex=429|IndexInSheet=23|OwnerPartId=-1|Location.X=439|Location.Y=742|Color=8388608|FontID=1|IsHidden=T|Text=Datasheet|Name=ComponentLink2Description
|RECORD=41|OwnerIndex=429|IndexInSheet=24|OwnerPartId=-1|Location.X=439|Location.Y=742|Color=8388608|FontID=1|IsHidden=T|Text=+125°C|Name=Temperature Range High
|RECORD=41|OwnerIndex=429|IndexInSheet=25|OwnerPartId=-1|Location.X=439|Location.Y=742|Color=8388608|FontID=1|IsHidden=T|Text=CAP CER 10000PF 50V X7R 0402|Name=Digikey Description
|RECORD=41|OwnerIndex=429|IndexInSheet=26|OwnerPartId=-1|Location.X=439|Location.Y=742|Color=8388608|FontID=1|IsHidden=T|Text=50 V|Name=Voltage Rating
|RECORD=41|OwnerIndex=429|IndexInSheet=27|OwnerPartId=-1|Location.X=439|Location.Y=742|Color=8388608|FontID=1|IsHidden=T|Text=NA|Name=Automotive Grade
|RECORD=41|OwnerIndex=429|IndexInSheet=28|OwnerPartId=-1|Location.X=439|Location.Y=742|Color=8388608|FontID=1|IsHidden=T|Text=CC0402|Name=Package
|RECORD=41|OwnerIndex=429|IndexInSheet=29|OwnerPartId=-1|Location.X=439|Location.Y=742|Color=8388608|FontID=1|IsHidden=T|Text=Capacitors|Name=Device Class L2
|RECORD=41|OwnerIndex=429|IndexInSheet=30|OwnerPartId=-1|Location.X=439|Location.Y=742|Color=8388608|FontID=1|IsHidden=T|Text=0402 10 nF 50 V ±10 % Tolerance X7R SMT Multilayer Ceramic Capacitor|Name=Mouser Description
|RECORD=41|OwnerIndex=429|IndexInSheet=31|OwnerPartId=-1|Location.X=439|Location.Y=742|Color=8388608|FontID=1|IsHidden=T|Text=0.1|Name=Tolerance
|RECORD=41|OwnerIndex=429|IndexInSheet=32|OwnerPartId=-1|Location.X=439|Location.Y=742|Color=8388608|FontID=1|IsHidden=T|Text=10 nF|Name=Value
|RECORD=41|OwnerIndex=429|IndexInSheet=33|OwnerPartId=-1|Location.X=439|Location.Y=742|Color=8388608|FontID=1|IsHidden=T|Text=TRUE|Name=RoHS
|RECORD=41|OwnerIndex=429|IndexInSheet=34|OwnerPartId=-1|Location.X=439|Location.Y=742|Color=8388608|FontID=1|IsHidden=T|Text=X7R|Name=Temperature Characteristic
|RECORD=34|OwnerIndex=429|IndexInSheet=-1|OwnerPartId=-1|Location.X=440|Location.Y=720|Orientation=1|Color=8388608|FontID=2|Text=C91|Name=Designator|ReadOnlyState=1
|RECORD=41|OwnerIndex=429|IndexInSheet=-1|OwnerPartId=1|Location.X=470|Location.Y=700|Orientation=1|Color=8388608|FontID=2|Text=10nF_50V_0402|Name=Comment
|RECORD=44|OwnerIndex=429
|RECORD=45|OwnerIndex=469|IndexInSheet=-1|UseComponentLibrary=T|ModelName=FP-CC0402-MFG|ModelType=PCBLIB|DatafileCount=1|ModelDatafileEntity0=FP-CC0402-MFG|ModelDatafileKind0=PCBLib|IsCurrent=T|DatalinksLocked=T|DatabaseDatalinksLocked=T
|RECORD=46|OwnerIndex=470
|RECORD=48|OwnerIndex=470
|RECORD=45|OwnerIndex=469|IndexInSheet=-1|UseComponentLibrary=T|ModelName=FP-CC0402-IPC_C|ModelType=PCBLIB|DatafileCount=1|ModelDatafileEntity0=FP-CC0402-IPC_C|ModelDatafileKind0=PCBLib|DatalinksLocked=T|DatabaseDatalinksLocked=T
|RECORD=46|OwnerIndex=473
|RECORD=48|OwnerIndex=473
|RECORD=45|OwnerIndex=469|IndexInSheet=-1|UseComponentLibrary=T|ModelName=FP-CC0402-IPC_B|ModelType=PCBLIB|DatafileCount=1|ModelDatafileEntity0=FP-CC0402-IPC_B|ModelDatafileKind0=PCBLib|DatalinksLocked=T|DatabaseDatalinksLocked=T
|RECORD=46|OwnerIndex=476
|RECORD=48|OwnerIndex=476
|RECORD=45|OwnerIndex=469|IndexInSheet=-1|UseComponentLibrary=T|ModelName=FP-CC0402-IPC_A|ModelType=PCBLIB|DatafileCount=1|ModelDatafileEntity0=FP-CC0402-IPC_A|ModelDatafileKind0=PCBLib|DatalinksLocked=T|DatabaseDatalinksLocked=T
|RECORD=46|OwnerIndex=479
|RECORD=48|OwnerIndex=479
|RECORD=1|LibReference=RES|PartCount=2|DisplayModeCount=2|IndexInSheet=46|OwnerPartId=-1|Location.X=780|Location.Y=860|CurrentPartId=1|SourceLibraryName=Altium Content Vault|TargetFileName=*|AreaColor=11599871|Color=128|PartIDLocked=F|DesignItemId=CMP-2002-08434-1|AllPinCount=2
|RECORD=2|OwnerIndex=482|OwnerPartId=1|OwnerPartDisplayMode=1|FormalType=1|Electrical=4|PinConglomerate=32|PinLength=10|Location.X=800|Location.Y=850|Name=2|Designator=2|PinPropagationDelay=0.000000E+000
|RECORD=2|OwnerIndex=482|OwnerPartId=1|OwnerPartDisplayMode=1|FormalType=1|Electrical=4|PinConglomerate=34|PinLength=10|Location.X=780|Location.Y=850|Name=1|Designator=1|PinPropagationDelay=0.000000E+000
|RECORD=14|OwnerIndex=482|IsNotAccesible=T|IndexInSheet=2|OwnerPartId=1|OwnerPartDisplayMode=1|Location.X=780|Location.Y=846|Corner.X=800|Corner.Y=854|LineWidth=1|Color=16711680|AreaColor=11599871
|RECORD=2|OwnerIndex=482|OwnerPartId=1|FormalType=1|Electrical=4|PinConglomerate=32|PinLength=10|Location.X=800|Location.Y=850|Name=2|Designator=2|PinPropagationDelay=0.000000E+000
|RECORD=2|OwnerIndex=482|OwnerPartId=1|FormalType=1|Electrical=4|PinConglomerate=34|PinLength=10|Location.X=780|Location.Y=850|Name=1|Designator=1|PinPropagationDelay=0.000000E+000
|RECORD=6|OwnerIndex=482|IsNotAccesible=T|IndexInSheet=5|OwnerPartId=1|LineWidth=1|Color=16711680|LocationCount=10|X1=800|Y1=850|X2=796|Y2=850|X3=795|Y3=848|X4=793|Y4=852|X5=791|Y5=848|X6=789|Y6=852|X7=787|Y7=848|X8=785|Y8=852|X9=784|Y9=850|X10=780|Y10=850
|RECORD=41|OwnerIndex=482|IndexInSheet=6|OwnerPartId=-1|Location.X=768|Location.Y=863|Color=8388608|FontID=1|IsHidden=T|Text=CRCW040227R0FKED|Name=Part Number
|RECORD=41|OwnerIndex=482|IndexInSheet=7|OwnerPartId=-1|Location.X=768|Location.Y=863|Color=8388608|FontID=1|IsHidden=T|Text=Vishay Dale|Name=Manufacturer
|RECORD=34|OwnerIndex=482|IndexInSheet=-1|OwnerPartId=-1|Location.X=760|Location.Y=850|Color=8388608|FontID=1|Text=R13|Name=Designator|ReadOnlyState=1
|RECORD=41|OwnerIndex=482|IndexInSheet=-1|OwnerPartId=-1|Location.X=780|Location.Y=850|Color=8388608|FontID=1|Text=27_1%_0402|Name=Comment
|RECORD=44|OwnerIndex=482
|RECORD=45|OwnerIndex=497|IndexInSheet=-1|Description=Chip Resistor, 2-Leads, Body 1.00x0.50mm, IPC Medium Density|UseComponentLibrary=T|ModelName=RESC1005X40X25NL05T05|ModelType=PCBLIB|DatafileCount=1|ModelDatafileEntity0=RESC1005X40X25NL05T05|ModelDatafileKind0=PCBLib|IsCurrent=T|DatalinksLocked=T|DatabaseDatalinksLocked=T
|RECORD=46|OwnerIndex=498
|RECORD=48|OwnerIndex=498
|RECORD=41|OwnerIndex=500|IndexInSheet=-1|OwnerPartId=-1|Color=8388608|FontID=1|IsHidden=T|Text=2D|Name=Available Preview Images
|RECORD=45|OwnerIndex=497|IndexInSheet=-1|Description=Chip Resistor, 2-Leads, Body 1.00x0.50mm, IPC High Density|UseComponentLibrary=T|ModelName=RESC1005X40X25LL05T05|ModelType=PCBLIB|DatafileCount=1|ModelDatafileEntity0=RESC1005X40X25LL05T05|ModelDatafileKind0=PCBLib|DatalinksLocked=T|DatabaseDatalinksLocked=T
|RECORD=46|OwnerIndex=502
|RECORD=48|OwnerIndex=502
|RECORD=41|OwnerIndex=504|IndexInSheet=-1|OwnerPartId=-1|Color=8388608|FontID=1|IsHidden=T|Text=2D|Name=Available Preview Images
|RECORD=45|OwnerIndex=497|IndexInSheet=-1|Description=Chip Resistor, 2-Leads, Body 1.00x0.50mm, IPC Low Density|UseComponentLibrary=T|ModelName=RESC1005X40X25ML05T05|ModelType=PCBLIB|DatafileCount=1|ModelDatafileEntity0=RESC1005X40X25ML05T05|ModelDatafileKind0=PCBLib|DatalinksLocked=T|DatabaseDatalinksLocked=T
|RECORD=46|OwnerIndex=506
|RECORD=48|OwnerIndex=506
|RECORD=41|OwnerIndex=508|IndexInSheet=-1|OwnerPartId=-1|Color=8388608|FontID=1|IsHidden=T|Text=2D|Name=Available Preview Images
|RECORD=1|LibReference=RES|PartCount=2|DisplayModeCount=2|IndexInSheet=47|OwnerPartId=-1|Location.X=780|Location.Y=850|CurrentPartId=1|SourceLibraryName=Altium Content Vault|TargetFileName=*|AreaColor=11599871|Color=128|PartIDLocked=F|DesignItemId=CMP-2002-08434-1|AllPinCount=2
|RECORD=2|OwnerIndex=510|OwnerPartId=1|OwnerPartDisplayMode=1|FormalType=1|Electrical=4|PinConglomerate=32|PinLength=10|Location.X=800|Location.Y=840|Name=2|Designator=2|PinPropagationDelay=0.000000E+000
|RECORD=2|OwnerIndex=510|OwnerPartId=1|OwnerPartDisplayMode=1|FormalType=1|Electrical=4|PinConglomerate=34|PinLength=10|Location.X=780|Location.Y=840|Name=1|Designator=1|PinPropagationDelay=0.000000E+000
|RECORD=14|OwnerIndex=510|IsNotAccesible=T|IndexInSheet=2|OwnerPartId=1|OwnerPartDisplayMode=1|Location.X=780|Location.Y=836|Corner.X=800|Corner.Y=844|LineWidth=1|Color=16711680|AreaColor=11599871
|RECORD=2|OwnerIndex=510|OwnerPartId=1|FormalType=1|Electrical=4|PinConglomerate=32|PinLength=10|Location.X=800|Location.Y=840|Name=2|Designator=2|PinPropagationDelay=0.000000E+000
|RECORD=2|OwnerIndex=510|OwnerPartId=1|FormalType=1|Electrical=4|PinConglomerate=34|PinLength=10|Location.X=780|Location.Y=840|Name=1|Designator=1|PinPropagationDelay=0.000000E+000
|RECORD=6|OwnerIndex=510|IsNotAccesible=T|IndexInSheet=5|OwnerPartId=1|LineWidth=1|Color=16711680|LocationCount=10|X1=800|Y1=840|X2=796|Y2=840|X3=795|Y3=838|X4=793|Y4=842|X5=791|Y5=838|X6=789|Y6=842|X7=787|Y7=838|X8=785|Y8=842|X9=784|Y9=840|X10=780|Y10=840
|RECORD=41|OwnerIndex=510|IndexInSheet=6|OwnerPartId=-1|Location.X=768|Location.Y=853|Color=8388608|FontID=1|IsHidden=T|Text=CRCW040227R0FKED|Name=Part Number
|RECORD=41|OwnerIndex=510|IndexInSheet=7|OwnerPartId=-1|Location.X=768|Location.Y=853|Color=8388608|FontID=1|IsHidden=T|Text=Vishay Dale|Name=Manufacturer
|RECORD=34|OwnerIndex=510|IndexInSheet=-1|OwnerPartId=-1|Location.X=760|Location.Y=840|Color=8388608|FontID=1|Text=R42|Name=Designator|ReadOnlyState=1
|RECORD=41|OwnerIndex=510|IndexInSheet=-1|OwnerPartId=-1|Location.X=780|Location.Y=840|Color=8388608|FontID=1|Text=27_1%_0402|Name=Comment
|RECORD=44|OwnerIndex=510
|RECORD=45|OwnerIndex=525|IndexInSheet=-1|Description=Chip Resistor, 2-Leads, Body 1.00x0.50mm, IPC Medium Density|UseComponentLibrary=T|ModelName=RESC1005X40X25NL05T05|ModelType=PCBLIB|DatafileCount=1|ModelDatafileEntity0=RESC1005X40X25NL05T05|ModelDatafileKind0=PCBLib|IsCurrent=T|DatalinksLocked=T|DatabaseDatalinksLocked=T
|RECORD=46|OwnerIndex=526
|RECORD=48|OwnerIndex=526
|RECORD=41|OwnerIndex=528|IndexInSheet=-1|OwnerPartId=-1|Color=8388608|FontID=1|IsHidden=T|Text=2D|Name=Available Preview Images
|RECORD=45|OwnerIndex=525|IndexInSheet=-1|Description=Chip Resistor, 2-Leads, Body 1.00x0.50mm, IPC High Density|UseComponentLibrary=T|ModelName=RESC1005X40X25LL05T05|ModelType=PCBLIB|DatafileCount=1|ModelDatafileEntity0=RESC1005X40X25LL05T05|ModelDatafileKind0=PCBLib|DatalinksLocked=T|DatabaseDatalinksLocked=T
|RECORD=46|OwnerIndex=530
|RECORD=48|OwnerIndex=530
|RECORD=41|OwnerIndex=532|IndexInSheet=-1|OwnerPartId=-1|Color=8388608|FontID=1|IsHidden=T|Text=2D|Name=Available Preview Images
|RECORD=45|OwnerIndex=525|IndexInSheet=-1|Description=Chip Resistor, 2-Leads, Body 1.00x0.50mm, IPC Low Density|UseComponentLibrary=T|ModelName=RESC1005X40X25ML05T05|ModelType=PCBLIB|DatafileCount=1|ModelDatafileEntity0=RESC1005X40X25ML05T05|ModelDatafileKind0=PCBLib|DatalinksLocked=T|DatabaseDatalinksLocked=T
|RECORD=46|OwnerIndex=534
|RECORD=48|OwnerIndex=534
|RECORD=41|OwnerIndex=536|IndexInSheet=-1|OwnerPartId=-1|Color=8388608|FontID=1|IsHidden=T|Text=2D|Name=Available Preview Images
|RECORD=17|IndexInSheet=48|OwnerPartId=-1|Style=1|ShowNetName=T|Location.X=870|Location.Y=850|Color=255|FontID=1|Text=FTDI_TX|IsCrossSheetConnector=T
|RECORD=17|IndexInSheet=49|OwnerPartId=-1|ShowNetName=T|Location.X=870|Location.Y=840|Color=255|FontID=1|Text=FTDI_RX|IsCrossSheetConnector=T
|RECORD=1|LibReference=b4654b650e69147ec39a6b967a45e02|ComponentDescription=General Purpose Ceramic Capacitor, 0402, 100nF, 10%, X7R, 15%, 25V|PartCount=2|DisplayModeCount=1|IndexInSheet=50|OwnerPartId=-1|Location.X=340|Location.Y=770|CurrentPartId=1|LibraryPath=*|SourceLibraryName=Altium Content Vault|TargetFileName=*|AreaColor=11599871|Color=128|PartIDLocked=T|DesignItemId=CMP-2008-02519-2|AllPinCount=2
|RECORD=2|OwnerIndex=540|OwnerPartId=1|Electrical=4|PinConglomerate=49|PinLength=7|Location.X=340|Location.Y=763|Name=1|Designator=1|PinPropagationDelay=0.000000E+000
|RECORD=2|OwnerIndex=540|OwnerPartId=1|Electrical=4|PinConglomerate=51|PinLength=6|Location.X=340|Location.Y=756|Name=2|Designator=2|PinPropagationDelay=0.000000E+000
|RECORD=13|OwnerIndex=540|IsNotAccesible=T|IndexInSheet=2|OwnerPartId=1|Location.X=350|Location.Y=763|Corner.X=330|Corner.Y=763|LineWidth=1|Color=16711680
|RECORD=13|OwnerIndex=540|IsNotAccesible=T|IndexInSheet=3|OwnerPartId=1|Location.X=350|Location.Y=757|Corner.X=330|Corner.Y=757|LineWidth=1|Color=16711680
|RECORD=13|OwnerIndex=540|IsNotAccesible=T|IndexInSheet=4|OwnerPartId=1|Location.X=340|Location.Y=763|Corner.X=340|Corner.Y=766|LineWidth=1|Color=16711680
|RECORD=13|OwnerIndex=540|IsNotAccesible=T|IndexInSheet=5|OwnerPartId=1|Location.X=340|Location.Y=756|Corner.X=340|Corner.Y=755|LineWidth=1|Color=16711680
|RECORD=41|OwnerIndex=540|IndexInSheet=6|OwnerPartId=-1|Location.X=329|Location.Y=772|Color=8388608|FontID=1|IsHidden=T|Text=1|Name=Package Quantity
|RECORD=41|OwnerIndex=540|IndexInSheet=7|OwnerPartId=-1|Location.X=329|Location.Y=772|Color=8388608|FontID=1|IsHidden=T|Text=100nF|Name=Capacitance
|RECORD=41|OwnerIndex=540|IndexInSheet=8|OwnerPartId=-1|Location.X=329|Location.Y=772|Color=8388608|FontID=1|IsHidden=T|Text=-55°C|Name=Min Operating Temperature
|RECORD=41|OwnerIndex=540|IndexInSheet=9|OwnerPartId=-1|Location.X=329|Location.Y=772|Color=8388608|FontID=1|IsHidden=T|Text=25V|Name=Voltage
|RECORD=41|OwnerIndex=540|IndexInSheet=10|OwnerPartId=-1|Location.X=329|Location.Y=772|Color=8388608|FontID=1|IsHidden=T|Text=25V|Name=Voltage Rating
|RECORD=41|OwnerIndex=540|IndexInSheet=11|OwnerPartId=-1|Location.X=329|Location.Y=772|Color=8388608|FontID=1|IsHidden=T|Text=Flat|Name=Construction
|RECORD=41|OwnerIndex=540|IndexInSheet=12|OwnerPartId=-1|Location.X=329|Location.Y=772|Color=8388608|FontID=1|IsHidden=T|Text=125°C|Name=Max Operating Temperature
|RECORD=41|OwnerIndex=540|IndexInSheet=13|OwnerPartId=-1|Location.X=329|Location.Y=772|Color=8388608|FontID=1|IsHidden=T|Text=No|Name=Radiation Hardening
|RECORD=41|OwnerIndex=540|IndexInSheet=14|OwnerPartId=-1|Location.X=329|Location.Y=772|Color=8388608|FontID=1|IsHidden=T|Text=0.5mm|Name=Depth
|RECORD=41|OwnerIndex=540|IndexInSheet=15|OwnerPartId=-1|Location.X=329|Location.Y=772|Color=8388608|FontID=1|IsHidden=T|Text=0.022inch|Name=Thickness
|RECORD=41|OwnerIndex=540|IndexInSheet=16|OwnerPartId=-1|Location.X=329|Location.Y=772|Color=8388608|FontID=1|IsHidden=T|Text=25V|Name=Voltage Rating (DC)
|RECORD=41|OwnerIndex=540|IndexInSheet=17|OwnerPartId=-1|Location.X=329|Location.Y=772|Color=8388608|FontID=1|IsHidden=T|Text=2|Name=Number of Pins
|RECORD=41|OwnerIndex=540|IndexInSheet=18|OwnerPartId=-1|Location.X=329|Location.Y=772|Color=8388608|FontID=1|IsHidden=T|Text=Lead Free|Name=Lead Free
|RECORD=41|OwnerIndex=540|IndexInSheet=19|OwnerPartId=-1|Location.X=329|Location.Y=772|Color=8388608|FontID=1|IsHidden=T|Text=-|Name=Series
|RECORD=41|OwnerIndex=540|IndexInSheet=20|OwnerPartId=-1|Location.X=329|Location.Y=772|Color=8388608|FontID=1|IsHidden=T|Text=No SVHC|Name=REACH SVHC
|RECORD=41|OwnerIndex=540|IndexInSheet=21|OwnerPartId=-1|Location.X=329|Location.Y=772|Color=8388608|FontID=1|IsHidden=T|Text=1mm|Name=Length
|RECORD=41|OwnerIndex=540|IndexInSheet=22|OwnerPartId=-1|Location.X=329|Location.Y=772|Color=8388608|FontID=1|IsHidden=T|Text=X7R|Name=Dielectric
|RECORD=41|OwnerIndex=540|IndexInSheet=23|OwnerPartId=-1|Location.X=329|Location.Y=772|Color=8388608|FontID=1|IsHidden=T|Text=Yes|Name=RoHS Compliant
|RECORD=41|OwnerIndex=540|IndexInSheet=24|OwnerPartId=-1|Location.X=329|Location.Y=772|Color=8388608|FontID=1|IsHidden=T|Text=Surface Mount|Name=Mount
|RECORD=41|OwnerIndex=540|IndexInSheet=25|OwnerPartId=-1|Location.X=329|Location.Y=772|Color=8388608|FontID=1|IsHidden=T|Text=Tape and Reel|Name=Packaging
|RECORD=41|OwnerIndex=540|IndexInSheet=26|OwnerPartId=-1|Location.X=329|Location.Y=772|Color=8388608|FontID=1|IsHidden=T|Text=0402|Name=Case/Package
|RECORD=41|OwnerIndex=540|IndexInSheet=27|OwnerPartId=-1|Location.X=329|Location.Y=772|Color=8388608|FontID=1|IsHidden=T|Text=0402|Name=Case Code (Imperial)
|RECORD=41|OwnerIndex=540|IndexInSheet=28|OwnerPartId=-1|Location.X=329|Location.Y=772|Color=8388608|FontID=1|IsHidden=T|Text=SMD/SMT|Name=Termination
|RECORD=41|OwnerIndex=540|IndexInSheet=29|OwnerPartId=-1|Location.X=329|Location.Y=772|Color=8388608|FontID=1|IsHidden=T|Text=0.02inch|Name=Width
|RECORD=41|OwnerIndex=540|IndexInSheet=30|OwnerPartId=-1|Location.X=329|Location.Y=772|Color=8388608|FontID=1|IsHidden=T|Text=1005|Name=Case Code (Metric)
|RECORD=41|OwnerIndex=540|IndexInSheet=31|OwnerPartId=-1|Location.X=329|Location.Y=772|Color=8388608|FontID=1|IsHidden=T|Text=10%|Name=Tolerance
|RECORD=34|OwnerIndex=540|IndexInSheet=-1|OwnerPartId=-1|Location.X=330|Location.Y=750|Orientation=1|Color=8388608|FontID=2|Text=C89|Name=Designator|ReadOnlyState=1
|RECORD=41|OwnerIndex=540|IndexInSheet=-1|OwnerPartId=1|Location.X=360|Location.Y=735|Orientation=1|Color=8388608|FontID=2|Text=0.1uF_25V_0402|Name=Comment
|RECORD=44|OwnerIndex=540
|RECORD=45|OwnerIndex=577|IndexInSheet=-1|UseComponentLibrary=T|ModelName=FP-0402-L_1_0_1-W_0_5_0_1-IPC_C|ModelType=PCBLIB|DatafileCount=1|ModelDatafileEntity0=FP-0402-L_1_0_1-W_0_5_0_1-IPC_C|ModelDatafileKind0=PCBLib|IsCurrent=T|DatalinksLocked=T|DatabaseDatalinksLocked=T
|RECORD=46|OwnerIndex=578
|RECORD=48|OwnerIndex=578
|RECORD=45|OwnerIndex=577|IndexInSheet=-1|UseComponentLibrary=T|ModelName=FP-0402-L_1_0_1-W_0_5_0_1-IPC_B|ModelType=PCBLIB|DatafileCount=1|ModelDatafileEntity0=FP-0402-L_1_0_1-W_0_5_0_1-IPC_B|ModelDatafileKind0=PCBLib|DatalinksLocked=T|DatabaseDatalinksLocked=T
|RECORD=46|OwnerIndex=581
|RECORD=48|OwnerIndex=581
|RECORD=45|OwnerIndex=577|IndexInSheet=-1|UseComponentLibrary=T|ModelName=FP-0402-L_1_0_1-W_0_5_0_1-MFG|ModelType=PCBLIB|DatafileCount=1|ModelDatafileEntity0=FP-0402-L_1_0_1-W_0_5_0_1-MFG|ModelDatafileKind0=PCBLib|DatalinksLocked=T|DatabaseDatalinksLocked=T
|RECORD=46|OwnerIndex=584
|RECORD=48|OwnerIndex=584
|RECORD=45|OwnerIndex=577|IndexInSheet=-1|UseComponentLibrary=T|ModelName=FP-0402-L_1_0_1-W_0_5_0_1-IPC_A|ModelType=PCBLIB|DatafileCount=1|ModelDatafileEntity0=FP-0402-L_1_0_1-W_0_5_0_1-IPC_A|ModelDatafileKind0=PCBLib|DatalinksLocked=T|DatabaseDatalinksLocked=T
|RECORD=46|OwnerIndex=587
|RECORD=48|OwnerIndex=587
|RECORD=1|LibReference=b4654b650e69147ec39a6b967a45e02|ComponentDescription=Cap Ceramic 4.7uF 16V X5R ±20% SMD 0402 +85°C Paper T/R|PartCount=2|DisplayModeCount=1|IndexInSheet=51|OwnerPartId=-1|Location.X=380|Location.Y=770|CurrentPartId=1|LibraryPath=*|SourceLibraryName=Altium Content Vault|TargetFileName=*|AreaColor=11599871|Color=128|PartIDLocked=T|DesignItemId=CMP-13271-001468-1|AllPinCount=2
|RECORD=2|OwnerIndex=590|OwnerPartId=1|Electrical=4|PinConglomerate=49|PinLength=7|Location.X=380|Location.Y=763|Name=1|Designator=1|PinPropagationDelay=0.000000E+000
|RECORD=2|OwnerIndex=590|OwnerPartId=1|Electrical=4|PinConglomerate=51|PinLength=6|Location.X=380|Location.Y=756|Name=2|Designator=2|PinPropagationDelay=0.000000E+000
|RECORD=13|OwnerIndex=590|IsNotAccesible=T|IndexInSheet=2|OwnerPartId=1|Location.X=390|Location.Y=763|Corner.X=370|Corner.Y=763|LineWidth=1|Color=16711680
|RECORD=13|OwnerIndex=590|IsNotAccesible=T|IndexInSheet=3|OwnerPartId=1|Location.X=390|Location.Y=757|Corner.X=370|Corner.Y=757|LineWidth=1|Color=16711680
|RECORD=13|OwnerIndex=590|IsNotAccesible=T|IndexInSheet=4|OwnerPartId=1|Location.X=380|Location.Y=763|Corner.X=380|Corner.Y=766|LineWidth=1|Color=16711680
|RECORD=13|OwnerIndex=590|IsNotAccesible=T|IndexInSheet=5|OwnerPartId=1|Location.X=380|Location.Y=756|Corner.X=380|Corner.Y=755|LineWidth=1|Color=16711680
|RECORD=41|OwnerIndex=590|IndexInSheet=6|OwnerPartId=-1|Location.X=369|Location.Y=772|Color=8388608|FontID=1|IsHidden=T|Text=Surface Mount|Name=Mount
|RECORD=41|OwnerIndex=590|IndexInSheet=7|OwnerPartId=-1|Location.X=369|Location.Y=772|Color=8388608|FontID=1|IsHidden=T|Text=1005|Name=Case Code (Metric)
|RECORD=41|OwnerIndex=590|IndexInSheet=8|OwnerPartId=-1|Location.X=369|Location.Y=772|Color=8388608|FontID=1|IsHidden=T|Text=0402|Name=Case/Package
|RECORD=41|OwnerIndex=590|IndexInSheet=9|OwnerPartId=-1|Location.X=369|Location.Y=772|Color=8388608|FontID=1|IsHidden=T|Text=0.039inch|Name=Length
|RECORD=41|OwnerIndex=590|IndexInSheet=10|OwnerPartId=-1|Location.X=369|Location.Y=772|Color=8388608|FontID=1|IsHidden=T|Text=4.7uF|Name=Capacitance
|RECORD=41|OwnerIndex=590|IndexInSheet=11|OwnerPartId=-1|Location.X=369|Location.Y=772|Color=8388608|FontID=1|IsHidden=T|Text=16V|Name=Voltage Rating
|RECORD=41|OwnerIndex=590|IndexInSheet=12|OwnerPartId=-1|Location.X=369|Location.Y=772|Color=8388608|FontID=1|IsHidden=T|Text=85°C|Name=Max Operating Temperature
|RECORD=41|OwnerIndex=590|IndexInSheet=13|OwnerPartId=-1|Location.X=369|Location.Y=772|Color=8388608|FontID=1|IsHidden=T|Text=20%|Name=Tolerance
|RECORD=41|OwnerIndex=590|IndexInSheet=14|OwnerPartId=-1|Location.X=369|Location.Y=772|Color=8388608|FontID=1|IsHidden=T|Text=0.022inch|Name=Thickness
|RECORD=41|OwnerIndex=590|IndexInSheet=15|OwnerPartId=-1|Location.X=369|Location.Y=772|Color=8388608|FontID=1|IsHidden=T|Text=-55°C|Name=Min Operating Temperature
|RECORD=41|OwnerIndex=590|IndexInSheet=16|OwnerPartId=-1|Location.X=369|Location.Y=772|Color=8388608|FontID=1|IsHidden=T|Text=0402|Name=Case Code (Imperial)
|RECORD=41|OwnerIndex=590|IndexInSheet=17|OwnerPartId=-1|Location.X=369|Location.Y=772|Color=8388608|FontID=1|IsHidden=T|Text=Tape and Reel|Name=Packaging
|RECORD=41|OwnerIndex=590|IndexInSheet=18|OwnerPartId=-1|Location.X=369|Location.Y=772|Color=8388608|FontID=1|IsHidden=T|Text=0.02inch|Name=Width
|RECORD=34|OwnerIndex=590|IndexInSheet=-1|OwnerPartId=-1|Location.X=370|Location.Y=750|Orientation=1|Color=8388608|FontID=2|Text=C90|Name=Designator|ReadOnlyState=1
|RECORD=41|OwnerIndex=590|IndexInSheet=-1|OwnerPartId=1|Location.X=400|Location.Y=730|Orientation=1|Color=8388608|FontID=2|Text=4.7uF_16V_0402|Name=Comment
|RECORD=44|OwnerIndex=590
|RECORD=45|OwnerIndex=614|IndexInSheet=-1|UseComponentLibrary=T|ModelName=FP-CL829-IPC_C|ModelType=PCBLIB|DatafileCount=1|ModelDatafileEntity0=FP-CL829-IPC_C|ModelDatafileKind0=PCBLib|IsCurrent=T|DatalinksLocked=T|DatabaseDatalinksLocked=T
|RECORD=46|OwnerIndex=615
|RECORD=48|OwnerIndex=615
|RECORD=45|OwnerIndex=614|IndexInSheet=-1|UseComponentLibrary=T|ModelName=FP-CL829-IPC_B|ModelType=PCBLIB|DatafileCount=1|ModelDatafileEntity0=FP-CL829-IPC_B|ModelDatafileKind0=PCBLib|DatalinksLocked=T|DatabaseDatalinksLocked=T
|RECORD=46|OwnerIndex=618
|RECORD=48|OwnerIndex=618
|RECORD=45|OwnerIndex=614|IndexInSheet=-1|UseComponentLibrary=T|ModelName=FP-CL829-IPC_A|ModelType=PCBLIB|DatafileCount=1|ModelDatafileEntity0=FP-CL829-IPC_A|ModelDatafileKind0=PCBLib|DatalinksLocked=T|DatabaseDatalinksLocked=T
|RECORD=46|OwnerIndex=621
|RECORD=48|OwnerIndex=621
|RECORD=1|LibReference=b4654b650e69147ec39a6b967a45e02|ComponentDescription=General Purpose Ceramic Capacitor, 0402, 100nF, 10%, X7R, 15%, 25V|PartCount=2|DisplayModeCount=1|IndexInSheet=52|OwnerPartId=-1|Location.X=590|Location.Y=720|CurrentPartId=1|LibraryPath=*|SourceLibraryName=Altium Content Vault|TargetFileName=*|AreaColor=11599871|Color=128|PartIDLocked=T|DesignItemId=CMP-2008-02519-2|AllPinCount=2
|RECORD=2|OwnerIndex=624|OwnerPartId=1|Electrical=4|PinConglomerate=49|PinLength=7|Location.X=590|Location.Y=713|Name=1|Designator=1|PinPropagationDelay=0.000000E+000
|RECORD=2|OwnerIndex=624|OwnerPartId=1|Electrical=4|PinConglomerate=51|PinLength=6|Location.X=590|Location.Y=706|Name=2|Designator=2|PinPropagationDelay=0.000000E+000
|RECORD=13|OwnerIndex=624|IsNotAccesible=T|IndexInSheet=2|OwnerPartId=1|Location.X=600|Location.Y=713|Corner.X=580|Corner.Y=713|LineWidth=1|Color=16711680
|RECORD=13|OwnerIndex=624|IsNotAccesible=T|IndexInSheet=3|OwnerPartId=1|Location.X=600|Location.Y=707|Corner.X=580|Corner.Y=707|LineWidth=1|Color=16711680
|RECORD=13|OwnerIndex=624|IsNotAccesible=T|IndexInSheet=4|OwnerPartId=1|Location.X=590|Location.Y=713|Corner.X=590|Corner.Y=716|LineWidth=1|Color=16711680
|RECORD=13|OwnerIndex=624|IsNotAccesible=T|IndexInSheet=5|OwnerPartId=1|Location.X=590|Location.Y=706|Corner.X=590|Corner.Y=705|LineWidth=1|Color=16711680
|RECORD=41|OwnerIndex=624|IndexInSheet=6|OwnerPartId=-1|Location.X=579|Location.Y=722|Color=8388608|FontID=1|IsHidden=T|Text=1|Name=Package Quantity
|RECORD=41|OwnerIndex=624|IndexInSheet=7|OwnerPartId=-1|Location.X=579|Location.Y=722|Color=8388608|FontID=1|IsHidden=T|Text=100nF|Name=Capacitance
|RECORD=41|OwnerIndex=624|IndexInSheet=8|OwnerPartId=-1|Location.X=579|Location.Y=722|Color=8388608|FontID=1|IsHidden=T|Text=-55°C|Name=Min Operating Temperature
|RECORD=41|OwnerIndex=624|IndexInSheet=9|OwnerPartId=-1|Location.X=579|Location.Y=722|Color=8388608|FontID=1|IsHidden=T|Text=25V|Name=Voltage
|RECORD=41|OwnerIndex=624|IndexInSheet=10|OwnerPartId=-1|Location.X=579|Location.Y=722|Color=8388608|FontID=1|IsHidden=T|Text=25V|Name=Voltage Rating
|RECORD=41|OwnerIndex=624|IndexInSheet=11|OwnerPartId=-1|Location.X=579|Location.Y=722|Color=8388608|FontID=1|IsHidden=T|Text=Flat|Name=Construction
|RECORD=41|OwnerIndex=624|IndexInSheet=12|OwnerPartId=-1|Location.X=579|Location.Y=722|Color=8388608|FontID=1|IsHidden=T|Text=125°C|Name=Max Operating Temperature
|RECORD=41|OwnerIndex=624|IndexInSheet=13|OwnerPartId=-1|Location.X=579|Location.Y=722|Color=8388608|FontID=1|IsHidden=T|Text=No|Name=Radiation Hardening
|RECORD=41|OwnerIndex=624|IndexInSheet=14|OwnerPartId=-1|Location.X=579|Location.Y=722|Color=8388608|FontID=1|IsHidden=T|Text=0.5mm|Name=Depth
|RECORD=41|OwnerIndex=624|IndexInSheet=15|OwnerPartId=-1|Location.X=579|Location.Y=722|Color=8388608|FontID=1|IsHidden=T|Text=0.022inch|Name=Thickness
|RECORD=41|OwnerIndex=624|IndexInSheet=16|OwnerPartId=-1|Location.X=579|Location.Y=722|Color=8388608|FontID=1|IsHidden=T|Text=25V|Name=Voltage Rating (DC)
|RECORD=41|OwnerIndex=624|IndexInSheet=17|OwnerPartId=-1|Location.X=579|Location.Y=722|Color=8388608|FontID=1|IsHidden=T|Text=2|Name=Number of Pins
|RECORD=41|OwnerIndex=624|IndexInSheet=18|OwnerPartId=-1|Location.X=579|Location.Y=722|Color=8388608|FontID=1|IsHidden=T|Text=Lead Free|Name=Lead Free
|RECORD=41|OwnerIndex=624|IndexInSheet=19|OwnerPartId=-1|Location.X=579|Location.Y=722|Color=8388608|FontID=1|IsHidden=T|Text=-|Name=Series
|RECORD=41|OwnerIndex=624|IndexInSheet=20|OwnerPartId=-1|Location.X=579|Location.Y=722|Color=8388608|FontID=1|IsHidden=T|Text=No SVHC|Name=REACH SVHC
|RECORD=41|OwnerIndex=624|IndexInSheet=21|OwnerPartId=-1|Location.X=579|Location.Y=722|Color=8388608|FontID=1|IsHidden=T|Text=1mm|Name=Length
|RECORD=41|OwnerIndex=624|IndexInSheet=22|OwnerPartId=-1|Location.X=579|Location.Y=722|Color=8388608|FontID=1|IsHidden=T|Text=X7R|Name=Dielectric
|RECORD=41|OwnerIndex=624|IndexInSheet=23|OwnerPartId=-1|Location.X=579|Location.Y=722|Color=8388608|FontID=1|IsHidden=T|Text=Yes|Name=RoHS Compliant
|RECORD=41|OwnerIndex=624|IndexInSheet=24|OwnerPartId=-1|Location.X=579|Location.Y=722|Color=8388608|FontID=1|IsHidden=T|Text=Surface Mount|Name=Mount
|RECORD=41|OwnerIndex=624|IndexInSheet=25|OwnerPartId=-1|Location.X=579|Location.Y=722|Color=8388608|FontID=1|IsHidden=T|Text=Tape and Reel|Name=Packaging
|RECORD=41|OwnerIndex=624|IndexInSheet=26|OwnerPartId=-1|Location.X=579|Location.Y=722|Color=8388608|FontID=1|IsHidden=T|Text=0402|Name=Case/Package
|RECORD=41|OwnerIndex=624|IndexInSheet=27|OwnerPartId=-1|Location.X=579|Location.Y=722|Color=8388608|FontID=1|IsHidden=T|Text=0402|Name=Case Code (Imperial)
|RECORD=41|OwnerIndex=624|IndexInSheet=28|OwnerPartId=-1|Location.X=579|Location.Y=722|Color=8388608|FontID=1|IsHidden=T|Text=SMD/SMT|Name=Termination
|RECORD=41|OwnerIndex=624|IndexInSheet=29|OwnerPartId=-1|Location.X=579|Location.Y=722|Color=8388608|FontID=1|IsHidden=T|Text=0.02inch|Name=Width
|RECORD=41|OwnerIndex=624|IndexInSheet=30|OwnerPartId=-1|Location.X=579|Location.Y=722|Color=8388608|FontID=1|IsHidden=T|Text=1005|Name=Case Code (Metric)
|RECORD=41|OwnerIndex=624|IndexInSheet=31|OwnerPartId=-1|Location.X=579|Location.Y=722|Color=8388608|FontID=1|IsHidden=T|Text=10%|Name=Tolerance
|RECORD=34|OwnerIndex=624|IndexInSheet=-1|OwnerPartId=-1|Location.X=580|Location.Y=700|Orientation=1|Color=8388608|FontID=2|Text=C93|Name=Designator|ReadOnlyState=1
|RECORD=41|OwnerIndex=624|IndexInSheet=-1|OwnerPartId=1|Location.X=610|Location.Y=685|Orientation=1|Color=8388608|FontID=2|Text=0.1uF_25V_0402|Name=Comment
|RECORD=44|OwnerIndex=624
|RECORD=45|OwnerIndex=661|IndexInSheet=-1|UseComponentLibrary=T|ModelName=FP-0402-L_1_0_1-W_0_5_0_1-IPC_C|ModelType=PCBLIB|DatafileCount=1|ModelDatafileEntity0=FP-0402-L_1_0_1-W_0_5_0_1-IPC_C|ModelDatafileKind0=PCBLib|IsCurrent=T|DatalinksLocked=T|DatabaseDatalinksLocked=T
|RECORD=46|OwnerIndex=662
|RECORD=48|OwnerIndex=662
|RECORD=45|OwnerIndex=661|IndexInSheet=-1|UseComponentLibrary=T|ModelName=FP-0402-L_1_0_1-W_0_5_0_1-IPC_B|ModelType=PCBLIB|DatafileCount=1|ModelDatafileEntity0=FP-0402-L_1_0_1-W_0_5_0_1-IPC_B|ModelDatafileKind0=PCBLib|DatalinksLocked=T|DatabaseDatalinksLocked=T
|RECORD=46|OwnerIndex=665
|RECORD=48|OwnerIndex=665
|RECORD=45|OwnerIndex=661|IndexInSheet=-1|UseComponentLibrary=T|ModelName=FP-0402-L_1_0_1-W_0_5_0_1-MFG|ModelType=PCBLIB|DatafileCount=1|ModelDatafileEntity0=FP-0402-L_1_0_1-W_0_5_0_1-MFG|ModelDatafileKind0=PCBLib|DatalinksLocked=T|DatabaseDatalinksLocked=T
|RECORD=46|OwnerIndex=668
|RECORD=48|OwnerIndex=668
|RECORD=45|OwnerIndex=661|IndexInSheet=-1|UseComponentLibrary=T|ModelName=FP-0402-L_1_0_1-W_0_5_0_1-IPC_A|ModelType=PCBLIB|DatafileCount=1|ModelDatafileEntity0=FP-0402-L_1_0_1-W_0_5_0_1-IPC_A|ModelDatafileKind0=PCBLib|DatalinksLocked=T|DatabaseDatalinksLocked=T
|RECORD=46|OwnerIndex=671
|RECORD=48|OwnerIndex=671
|RECORD=4|IndexInSheet=53|OwnerPartId=-1|Location.X=450|Location.Y=870|Color=8388608|FontID=1|Text=USB to UART
|RECORD=1|LibReference=070a973bb9dfaf4112c7cb8da95b8f6|ComponentDescription=SWITCH SLIDE DIP SPST 25MA 24V|PartCount=2|DisplayModeCount=1|IndexInSheet=54|OwnerPartId=-1|Location.X=130|Location.Y=470|CurrentPartId=1|LibraryPath=*|SourceLibraryName=Altium Content Vault|TargetFileName=*|AreaColor=11599871|Color=128|PartIDLocked=T|DesignItemId=CMP-08827-000068-1|AllPinCount=4
|RECORD=14|OwnerIndex=675|IsNotAccesible=T|OwnerPartId=1|Location.X=150|Location.Y=430|Corner.X=190|Corner.Y=490|LineWidth=1|Color=128|AreaColor=11599871|IsSolid=T
|RECORD=8|OwnerIndex=675|IsNotAccesible=T|IndexInSheet=1|OwnerPartId=1|Location.X=163|Location.Y=470|Radius=2|SecondaryRadius=2|LineWidth=1|Color=16711680
|RECORD=8|OwnerIndex=675|IsNotAccesible=T|IndexInSheet=2|OwnerPartId=1|Location.X=177|Location.Y=470|Radius=2|SecondaryRadius=2|LineWidth=1|Color=16711680
|RECORD=13|OwnerIndex=675|IsNotAccesible=T|IndexInSheet=3|OwnerPartId=1|Location.X=165|Location.Y=471|Corner.X=175|Corner.Y=477|LineWidth=1|Color=16711680
|RECORD=13|OwnerIndex=675|IsNotAccesible=T|IndexInSheet=4|OwnerPartId=1|Location.X=165|Location.Y=451|Corner.X=175|Corner.Y=457|LineWidth=1|Color=16711680
|RECORD=8|OwnerIndex=675|IsNotAccesible=T|IndexInSheet=5|OwnerPartId=1|Location.X=163|Location.Y=450|Radius=2|SecondaryRadius=2|LineWidth=1|Color=16711680
|RECORD=8|OwnerIndex=675|IsNotAccesible=T|IndexInSheet=6|OwnerPartId=1|Location.X=177|Location.Y=450|Radius=2|SecondaryRadius=2|LineWidth=1|Color=16711680
|RECORD=13|OwnerIndex=675|IsNotAccesible=T|IndexInSheet=7|OwnerPartId=1|Location.X=160|Location.Y=470|Corner.X=150|Corner.Y=470|LineWidth=1|Color=16711680
|RECORD=13|OwnerIndex=675|IsNotAccesible=T|IndexInSheet=8|OwnerPartId=1|Location.X=160|Location.Y=450|Corner.X=150|Corner.Y=450|LineWidth=1|Color=16711680
|RECORD=13|OwnerIndex=675|IsNotAccesible=T|IndexInSheet=9|OwnerPartId=1|Location.X=180|Location.Y=450|Corner.X=190|Corner.Y=450|LineWidth=1|Color=16711680
|RECORD=13|OwnerIndex=675|IsNotAccesible=T|IndexInSheet=10|OwnerPartId=1|Location.X=180|Location.Y=470|Corner.X=190|Corner.Y=470|LineWidth=1|Color=16711680
|RECORD=2|OwnerIndex=675|OwnerPartId=1|Electrical=4|PinConglomerate=50|PinLength=20|Location.X=150|Location.Y=470|Name=1|Designator=1|PinName_PositionConglomerate=16|Name_CustomFontID=1|PinDesignator_PositionConglomerate=16|Designator_CustomFontID=1|PinPropagationDelay=0.000000E+000
|RECORD=2|OwnerIndex=675|OwnerPartId=1|Electrical=4|PinConglomerate=50|PinLength=20|Location.X=150|Location.Y=450|Name=2|Designator=2|PinName_PositionConglomerate=16|Name_CustomFontID=1|PinDesignator_PositionConglomerate=16|Designator_CustomFontID=1|PinPropagationDelay=0.000000E+000
|RECORD=2|OwnerIndex=675|OwnerPartId=1|Electrical=4|PinConglomerate=48|PinLength=20|Location.X=190|Location.Y=450|Name=3|Designator=3|PinName_PositionConglomerate=16|Name_CustomFontID=1|PinDesignator_PositionConglomerate=16|Designator_CustomFontID=1|PinPropagationDelay=0.000000E+000
|RECORD=2|OwnerIndex=675|OwnerPartId=1|Electrical=4|PinConglomerate=48|PinLength=20|Location.X=190|Location.Y=470|Name=4|Designator=4|PinName_PositionConglomerate=16|Name_CustomFontID=1|PinDesignator_PositionConglomerate=16|Designator_CustomFontID=1|PinPropagationDelay=0.000000E+000
|RECORD=41|OwnerIndex=675|IndexInSheet=15|OwnerPartId=-1|Location.X=128|Location.Y=490|Color=8388608|FontID=1|IsHidden=T|Text=0.06g|Name=Weight
|RECORD=41|OwnerIndex=675|IndexInSheet=16|OwnerPartId=-1|Location.X=128|Location.Y=490|Color=8388608|FontID=1|IsHidden=T|Text=Yes|Name=Washable
|RECORD=41|OwnerIndex=675|IndexInSheet=17|OwnerPartId=-1|Location.X=128|Location.Y=490|Color=8388608|FontID=1|IsHidden=T|Text=Straight|Name=Orientation
|RECORD=41|OwnerIndex=675|IndexInSheet=18|OwnerPartId=-1|Location.X=128|Location.Y=490|Color=8388608|FontID=1|IsHidden=T|Text=DIP|Name=Case/Package
|RECORD=41|OwnerIndex=675|IndexInSheet=19|OwnerPartId=-1|Location.X=128|Location.Y=490|Color=8388608|FontID=1|IsHidden=T|Text=25mA|Name=Contact Current Rating
|RECORD=41|OwnerIndex=675|IndexInSheet=20|OwnerPartId=-1|Location.X=128|Location.Y=490|Color=8388608|FontID=1|IsHidden=T|Text=2|Name=Number of Circuits
|RECORD=41|OwnerIndex=675|IndexInSheet=21|OwnerPartId=-1|Location.X=128|Location.Y=490|Color=8388608|FontID=1|IsHidden=T|Text=Gull Wing|Name=Termination
|RECORD=41|OwnerIndex=675|IndexInSheet=22|OwnerPartId=-1|Location.X=128|Location.Y=490|Color=8388608|FontID=1|IsHidden=T|Text=75|Name=Package Quantity
|RECORD=41|OwnerIndex=675|IndexInSheet=23|OwnerPartId=-1|Location.X=128|Location.Y=490|Color=8388608|FontID=1|IsHidden=T|Text=A6H|Name=Series
|RECORD=41|OwnerIndex=675|IndexInSheet=24|OwnerPartId=-1|Location.X=128|Location.Y=490|Color=8388608|FontID=1|IsHidden=T|Text=2|Name=Number of Positions
|RECORD=41|OwnerIndex=675|IndexInSheet=25|OwnerPartId=-1|Location.X=128|Location.Y=490|Color=8388608|FontID=1|IsHidden=T|Text=Slide (Standard)|Name=Actuator Type
|RECORD=41|OwnerIndex=675|IndexInSheet=26|OwnerPartId=-1|Location.X=128|Location.Y=490|Color=8388608|FontID=1|IsHidden=T|Text=25mA|Name=Current Rating
|RECORD=41|OwnerIndex=675|IndexInSheet=27|OwnerPartId=-1|Location.X=128|Location.Y=490|Color=8388608|FontID=1|IsHidden=T|Text=SPST|Name=Throw Configuration
|RECORD=41|OwnerIndex=675|IndexInSheet=28|OwnerPartId=-1|Location.X=128|Location.Y=490|Color=8388608|FontID=1|IsHidden=T|Text=1.55mm|Name=Height
|RECORD=41|OwnerIndex=675|IndexInSheet=29|OwnerPartId=-1|Location.X=128|Location.Y=490|Color=8388608|FontID=1|IsHidden=T|Text=200mR|Name=Contact Resistance
|RECORD=41|OwnerIndex=675|IndexInSheet=30|OwnerPartId=-1|Location.X=128|Location.Y=490|Color=8388608|FontID=1|IsHidden=T|Text=0.05inch|Name=Pitch
|RECORD=41|OwnerIndex=675|IndexInSheet=31|OwnerPartId=-1|Location.X=128|Location.Y=490|Color=8388608|FontID=1|IsHidden=T|Text=25mA|Name=Max Current Rating
|RECORD=41|OwnerIndex=675|IndexInSheet=32|OwnerPartId=-1|Location.X=128|Location.Y=490|Color=8388608|FontID=1|IsHidden=T|Text=0.148inch|Name=Length
|RECORD=41|OwnerIndex=675|IndexInSheet=33|OwnerPartId=-1|Location.X=128|Location.Y=490|Color=8388608|FontID=1|IsHidden=T|Text=Yes|Name=RoHS Compliant
|RECORD=41|OwnerIndex=675|IndexInSheet=34|OwnerPartId=-1|Location.X=128|Location.Y=490|Color=8388608|FontID=1|IsHidden=T|Text=24V|Name=Voltage Rating (DC)
|RECORD=41|OwnerIndex=675|IndexInSheet=35|OwnerPartId=-1|Location.X=128|Location.Y=490|Color=8388608|FontID=1|IsHidden=T|Text=1000Cycles|Name=Mechanical Life
|RECORD=41|OwnerIndex=675|IndexInSheet=36|OwnerPartId=-1|Location.X=128|Location.Y=490|Color=8388608|FontID=1|IsHidden=T|Text=Surface Mount|Name=Mount
|RECORD=41|OwnerIndex=675|IndexInSheet=37|OwnerPartId=-1|Location.X=128|Location.Y=490|Color=8388608|FontID=1|IsHidden=T|Text=24V|Name=Max Voltage Rating (DC)
|RECORD=41|OwnerIndex=675|IndexInSheet=38|OwnerPartId=-1|Location.X=128|Location.Y=490|Color=8388608|FontID=1|IsHidden=T|Text=0mm|Name=Actuator Length
|RECORD=41|OwnerIndex=675|IndexInSheet=39|OwnerPartId=-1|Location.X=128|Location.Y=490|Color=8388608|FontID=1|IsHidden=T|Text=70°C|Name=Max Operating Temperature
|RECORD=41|OwnerIndex=675|IndexInSheet=40|OwnerPartId=-1|Location.X=128|Location.Y=490|Color=8388608|FontID=1|IsHidden=T|Text=8|Name=Number of Poles
|RECORD=41|OwnerIndex=675|IndexInSheet=41|OwnerPartId=-1|Location.X=128|Location.Y=490|Color=8388608|FontID=1|IsHidden=T|Text=1.27mm|Name=Terminal Pitch
|RECORD=41|OwnerIndex=675|IndexInSheet=42|OwnerPartId=-1|Location.X=128|Location.Y=490|Color=8388608|FontID=1|IsHidden=T|Text=Rail/Tube|Name=Packaging
|RECORD=41|OwnerIndex=675|IndexInSheet=43|OwnerPartId=-1|Location.X=128|Location.Y=490|Color=8388608|FontID=1|IsHidden=T|Text=1000Cycles|Name=Electrical Life
|RECORD=41|OwnerIndex=675|IndexInSheet=44|OwnerPartId=-1|Location.X=128|Location.Y=490|Color=8388608|FontID=1|IsHidden=T|Text=-20°C|Name=Min Operating Temperature
|RECORD=41|OwnerIndex=675|IndexInSheet=45|OwnerPartId=-1|Location.X=128|Location.Y=490|Color=8388608|FontID=1|IsHidden=T|Text=4.5mm|Name=Width
|RECORD=34|OwnerIndex=675|IndexInSheet=-1|OwnerPartId=-1|Location.X=149|Location.Y=490|Color=8388608|FontID=1|Text=SW1|Name=Designator|ReadOnlyState=1
|RECORD=41|OwnerIndex=675|IndexInSheet=-1|OwnerPartId=1|Location.X=149|Location.Y=420|Color=8388608|FontID=1|Text=A6H-2102|Name=Comment
|RECORD=44|OwnerIndex=675
|RECORD=45|OwnerIndex=728|IndexInSheet=-1|UseComponentLibrary=T|ModelName=FP-A6H-2102-MFG|ModelType=PCBLIB|DatafileCount=1|ModelDatafileEntity0=FP-A6H-2102-MFG|ModelDatafileKind0=PCBLib|IsCurrent=T|DatalinksLocked=T|DatabaseDatalinksLocked=T
|RECORD=46|OwnerIndex=729
|RECORD=48|OwnerIndex=729
|RECORD=4|IndexInSheet=55|OwnerPartId=-1|Location.X=60|Location.Y=610|Color=8388608|FontID=1|Text=DIP Switch, Configure UART and PPS Single ended versus differential
|RECORD=17|IndexInSheet=56|OwnerPartId=-1|Style=4|ShowNetName=T|Location.X=110|Location.Y=430|Orientation=3|Color=128|FontID=1|Text=GND
|RECORD=17|IndexInSheet=57|OwnerPartId=-1|Style=1|ShowNetName=T|Location.X=290|Location.Y=470|Color=255|FontID=1|Text=DIP_SW_UART_SEL|IsCrossSheetConnector=T
|RECORD=17|IndexInSheet=58|OwnerPartId=-1|Style=1|ShowNetName=T|Location.X=290|Location.Y=450|Color=255|FontID=1|Text=DIP_SW_PPS_SEL|IsCrossSheetConnector=T
|RECORD=4|IndexInSheet=59|OwnerPartId=-1|Location.X=120|Location.Y=600|Color=8388608|FontID=1|Text=UART either goes to FPGA or to GPS2
|RECORD=1|LibReference=RES|PartCount=2|DisplayModeCount=2|IndexInSheet=60|OwnerPartId=-1|Location.X=240|Location.Y=510|Orientation=3|CurrentPartId=1|SourceLibraryName=Altium Content Vault|TargetFileName=*|AreaColor=11599871|Color=128|PartIDLocked=F|DesignItemId=CMP-2002-07353-1|AllPinCount=2
|RECORD=2|OwnerIndex=737|OwnerPartId=1|OwnerPartDisplayMode=1|FormalType=1|Electrical=4|PinConglomerate=35|PinLength=10|Location.X=230|Location.Y=490|Name=2|Designator=2|PinPropagationDelay=0.000000E+000
|RECORD=2|OwnerIndex=737|OwnerPartId=1|OwnerPartDisplayMode=1|FormalType=1|Electrical=4|PinConglomerate=33|PinLength=10|Location.X=230|Location.Y=510|Name=1|Designator=1|PinPropagationDelay=0.000000E+000
|RECORD=14|OwnerIndex=737|IsNotAccesible=T|IndexInSheet=2|OwnerPartId=1|OwnerPartDisplayMode=1|Location.X=226|Location.Y=490|Corner.X=234|Corner.Y=510|LineWidth=1|Color=16711680|AreaColor=11599871
|RECORD=2|OwnerIndex=737|OwnerPartId=1|FormalType=1|Electrical=4|PinConglomerate=35|PinLength=10|Location.X=230|Location.Y=490|Name=2|Designator=2|PinPropagationDelay=0.000000E+000
|RECORD=2|OwnerIndex=737|OwnerPartId=1|FormalType=1|Electrical=4|PinConglomerate=33|PinLength=10|Location.X=230|Location.Y=510|Name=1|Designator=1|PinPropagationDelay=0.000000E+000
|RECORD=6|OwnerIndex=737|IsNotAccesible=T|IndexInSheet=5|OwnerPartId=1|LineWidth=1|Color=16711680|LocationCount=10|X1=230|Y1=490|X2=230|Y2=494|X3=228|Y3=495|X4=232|Y4=497|X5=228|Y5=499|X6=232|Y6=501|X7=228|Y7=503|X8=232|Y8=505|X9=230|Y9=506|X10=230|Y10=510
|RECORD=41|OwnerIndex=737|IndexInSheet=6|OwnerPartId=-1|Location.X=227|Location.Y=522|Color=8388608|FontID=1|IsHidden=T|Text=RC0402FR-0710KL|Name=Part Number
|RECORD=41|OwnerIndex=737|IndexInSheet=7|OwnerPartId=-1|Location.X=227|Location.Y=522|Color=8388608|FontID=1|IsHidden=T|Text=Yageo / Phycomp|Name=Manufacturer
|RECORD=34|OwnerIndex=737|IndexInSheet=-1|OwnerPartId=-1|Location.X=230|Location.Y=480|Orientation=1|Color=8388608|FontID=2|Text=R88|Name=Designator|ReadOnlyState=1
|RECORD=41|OwnerIndex=737|IndexInSheet=-1|OwnerPartId=-1|Location.X=240|Location.Y=480|Orientation=1|Color=8388608|FontID=2|Text=10K_1%_0402|Name=Comment
|RECORD=44|OwnerIndex=737
|RECORD=45|OwnerIndex=752|IndexInSheet=-1|Description=Chip Resistor, 2-Leads, Body 1.00x0.50mm, IPC High Density|UseComponentLibrary=T|ModelName=RESC1005X40X25LL05T10|ModelType=PCBLIB|DatafileCount=1|ModelDatafileEntity0=RESC1005X40X25LL05T10|ModelDatafileKind0=PCBLib|IsCurrent=T|DatalinksLocked=T|DatabaseDatalinksLocked=T
|RECORD=46|OwnerIndex=753
|RECORD=48|OwnerIndex=753
|RECORD=41|OwnerIndex=755|IndexInSheet=-1|OwnerPartId=-1|Color=8388608|FontID=1|IsHidden=T|Text=2D|Name=Available Preview Images
|RECORD=45|OwnerIndex=752|IndexInSheet=-1|Description=Chip Resistor, 2-Leads, Body 1.00x0.50mm, IPC Low Density|UseComponentLibrary=T|ModelName=RESC1005X40X25ML05T10|ModelType=PCBLIB|DatafileCount=1|ModelDatafileEntity0=RESC1005X40X25ML05T10|ModelDatafileKind0=PCBLib|DatalinksLocked=T|DatabaseDatalinksLocked=T
|RECORD=46|OwnerIndex=757
|RECORD=48|OwnerIndex=757
|RECORD=41|OwnerIndex=759|IndexInSheet=-1|OwnerPartId=-1|Color=8388608|FontID=1|IsHidden=T|Text=2D|Name=Available Preview Images
|RECORD=45|OwnerIndex=752|IndexInSheet=-1|Description=Chip Resistor, 2-Leads, Body 1.00x0.50mm, IPC Medium Density|UseComponentLibrary=T|ModelName=RESC1005X40X25NL05T10|ModelType=PCBLIB|DatafileCount=1|ModelDatafileEntity0=RESC1005X40X25NL05T10|ModelDatafileKind0=PCBLib|DatalinksLocked=T|DatabaseDatalinksLocked=T
|RECORD=46|OwnerIndex=761
|RECORD=48|OwnerIndex=761
|RECORD=41|OwnerIndex=763|IndexInSheet=-1|OwnerPartId=-1|Color=8388608|FontID=1|IsHidden=T|Text=2D|Name=Available Preview Images
|RECORD=17|IndexInSheet=61|OwnerPartId=-1|ShowNetName=T|Location.X=230|Location.Y=540|Orientation=1|Color=128|FontID=1|Text=+3.3V
|RECORD=1|LibReference=RES|PartCount=2|DisplayModeCount=2|IndexInSheet=62|OwnerPartId=-1|Location.X=280|Location.Y=510|Orientation=3|CurrentPartId=1|SourceLibraryName=Altium Content Vault|TargetFileName=*|AreaColor=11599871|Color=128|PartIDLocked=F|DesignItemId=CMP-2002-07353-1|AllPinCount=2
|RECORD=2|OwnerIndex=766|OwnerPartId=1|OwnerPartDisplayMode=1|FormalType=1|Electrical=4|PinConglomerate=35|PinLength=10|Location.X=270|Location.Y=490|Name=2|Designator=2|PinPropagationDelay=0.000000E+000
|RECORD=2|OwnerIndex=766|OwnerPartId=1|OwnerPartDisplayMode=1|FormalType=1|Electrical=4|PinConglomerate=33|PinLength=10|Location.X=270|Location.Y=510|Name=1|Designator=1|PinPropagationDelay=0.000000E+000
|RECORD=14|OwnerIndex=766|IsNotAccesible=T|IndexInSheet=2|OwnerPartId=1|OwnerPartDisplayMode=1|Location.X=266|Location.Y=490|Corner.X=274|Corner.Y=510|LineWidth=1|Color=16711680|AreaColor=11599871
|RECORD=2|OwnerIndex=766|OwnerPartId=1|FormalType=1|Electrical=4|PinConglomerate=35|PinLength=10|Location.X=270|Location.Y=490|Name=2|Designator=2|PinPropagationDelay=0.000000E+000
|RECORD=2|OwnerIndex=766|OwnerPartId=1|FormalType=1|Electrical=4|PinConglomerate=33|PinLength=10|Location.X=270|Location.Y=510|Name=1|Designator=1|PinPropagationDelay=0.000000E+000
|RECORD=6|OwnerIndex=766|IsNotAccesible=T|IndexInSheet=5|OwnerPartId=1|LineWidth=1|Color=16711680|LocationCount=10|X1=270|Y1=490|X2=270|Y2=494|X3=268|Y3=495|X4=272|Y4=497|X5=268|Y5=499|X6=272|Y6=501|X7=268|Y7=503|X8=272|Y8=505|X9=270|Y9=506|X10=270|Y10=510
|RECORD=41|OwnerIndex=766|IndexInSheet=6|OwnerPartId=-1|Location.X=267|Location.Y=522|Color=8388608|FontID=1|IsHidden=T|Text=RC0402FR-0710KL|Name=Part Number
|RECORD=41|OwnerIndex=766|IndexInSheet=7|OwnerPartId=-1|Location.X=267|Location.Y=522|Color=8388608|FontID=1|IsHidden=T|Text=Yageo / Phycomp|Name=Manufacturer
|RECORD=34|OwnerIndex=766|IndexInSheet=-1|OwnerPartId=-1|Location.X=270|Location.Y=480|Orientation=1|Color=8388608|FontID=2|Text=R89|Name=Designator|ReadOnlyState=1
|RECORD=41|OwnerIndex=766|IndexInSheet=-1|OwnerPartId=-1|Location.X=280|Location.Y=480|Orientation=1|Color=8388608|FontID=2|Text=10K_1%_0402|Name=Comment
|RECORD=44|OwnerIndex=766
|RECORD=45|OwnerIndex=781|IndexInSheet=-1|Description=Chip Resistor, 2-Leads, Body 1.00x0.50mm, IPC High Density|UseComponentLibrary=T|ModelName=RESC1005X40X25LL05T10|ModelType=PCBLIB|DatafileCount=1|ModelDatafileEntity0=RESC1005X40X25LL05T10|ModelDatafileKind0=PCBLib|IsCurrent=T|DatalinksLocked=T|DatabaseDatalinksLocked=T
|RECORD=46|OwnerIndex=782
|RECORD=48|OwnerIndex=782
|RECORD=41|OwnerIndex=784|IndexInSheet=-1|OwnerPartId=-1|Color=8388608|FontID=1|IsHidden=T|Text=2D|Name=Available Preview Images
|RECORD=45|OwnerIndex=781|IndexInSheet=-1|Description=Chip Resistor, 2-Leads, Body 1.00x0.50mm, IPC Low Density|UseComponentLibrary=T|ModelName=RESC1005X40X25ML05T10|ModelType=PCBLIB|DatafileCount=1|ModelDatafileEntity0=RESC1005X40X25ML05T10|ModelDatafileKind0=PCBLib|DatalinksLocked=T|DatabaseDatalinksLocked=T
|RECORD=46|OwnerIndex=786
|RECORD=48|OwnerIndex=786
|RECORD=41|OwnerIndex=788|IndexInSheet=-1|OwnerPartId=-1|Color=8388608|FontID=1|IsHidden=T|Text=2D|Name=Available Preview Images
|RECORD=45|OwnerIndex=781|IndexInSheet=-1|Description=Chip Resistor, 2-Leads, Body 1.00x0.50mm, IPC Medium Density|UseComponentLibrary=T|ModelName=RESC1005X40X25NL05T10|ModelType=PCBLIB|DatafileCount=1|ModelDatafileEntity0=RESC1005X40X25NL05T10|ModelDatafileKind0=PCBLib|DatalinksLocked=T|DatabaseDatalinksLocked=T
|RECORD=46|OwnerIndex=790
|RECORD=48|OwnerIndex=790
|RECORD=41|OwnerIndex=792|IndexInSheet=-1|OwnerPartId=-1|Color=8388608|FontID=1|IsHidden=T|Text=2D|Name=Available Preview Images
|RECORD=17|IndexInSheet=63|OwnerPartId=-1|ShowNetName=T|Location.X=270|Location.Y=540|Orientation=1|Color=128|FontID=1|Text=+3.3V
|RECORD=1|LibReference=12a319ab100cd6cfe745e35972674f5|ComponentDescription=IC SWITCH SPDT DUAL 12UQFN|PartCount=2|DisplayModeCount=1|IndexInSheet=64|OwnerPartId=-1|Location.X=680|Location.Y=500|CurrentPartId=1|LibraryPath=*|SourceLibraryName=Altium Content Vault|TargetFileName=*|AreaColor=11599871|Color=128|PartIDLocked=T|DesignItemId=CMP-04892-000114-1|AllPinCount=12
|RECORD=14|OwnerIndex=795|IsNotAccesible=T|OwnerPartId=1|Location.X=700|Location.Y=340|Corner.X=800|Corner.Y=510|LineWidth=1|Color=128|AreaColor=11599871|IsSolid=T
|RECORD=2|OwnerIndex=795|OwnerPartId=1|Electrical=7|PinConglomerate=58|PinLength=20|Location.X=700|Location.Y=500|Name=VCC|Designator=9|PinName_PositionConglomerate=16|Name_CustomFontID=1|PinDesignator_PositionConglomerate=16|Designator_CustomFontID=1|PinPropagationDelay=0.000000E+000
|RECORD=2|OwnerIndex=795|OwnerPartId=1|PinConglomerate=58|PinLength=20|Location.X=700|Location.Y=400|Name=SEL1|Designator=1|PinName_PositionConglomerate=16|Name_CustomFontID=1|PinDesignator_PositionConglomerate=16|Designator_CustomFontID=1|PinPropagationDelay=0.000000E+000
|RECORD=2|OwnerIndex=795|OwnerPartId=1|PinConglomerate=58|PinLength=20|Location.X=700|Location.Y=390|Name=SEL2|Designator=5|PinName_PositionConglomerate=16|Name_CustomFontID=1|PinDesignator_PositionConglomerate=16|Designator_CustomFontID=1|PinPropagationDelay=0.000000E+000
|RECORD=2|OwnerIndex=795|OwnerPartId=1|Electrical=4|PinConglomerate=58|PinLength=20|Location.X=700|Location.Y=460|Name=NO1|Designator=2|PinName_PositionConglomerate=16|Name_CustomFontID=1|PinDesignator_PositionConglomerate=16|Designator_CustomFontID=1|PinPropagationDelay=0.000000E+000
|RECORD=2|OwnerIndex=795|OwnerPartId=1|Electrical=4|PinConglomerate=58|PinLength=20|Location.X=700|Location.Y=420|Name=NO2|Designator=4|PinName_PositionConglomerate=16|Name_CustomFontID=1|PinDesignator_PositionConglomerate=16|Designator_CustomFontID=1|PinPropagationDelay=0.000000E+000
|RECORD=2|OwnerIndex=795|OwnerPartId=1|Electrical=4|PinConglomerate=56|PinLength=20|Location.X=800|Location.Y=480|Name=COM1|Designator=11|PinName_PositionConglomerate=16|Name_CustomFontID=1|PinDesignator_PositionConglomerate=16|Designator_CustomFontID=1|PinPropagationDelay=0.000000E+000
|RECORD=2|OwnerIndex=795|OwnerPartId=1|Electrical=4|PinConglomerate=56|PinLength=20|Location.X=800|Location.Y=440|Name=COM2|Designator=7|PinName_PositionConglomerate=16|Name_CustomFontID=1|PinDesignator_PositionConglomerate=16|Designator_CustomFontID=1|PinPropagationDelay=0.000000E+000
|RECORD=2|OwnerIndex=795|OwnerPartId=1|Electrical=3|PinConglomerate=58|PinLength=20|Location.X=700|Location.Y=350|Name=F\L\T\|Designator=12|PinName_PositionConglomerate=16|Name_CustomFontID=1|PinDesignator_PositionConglomerate=16|Designator_CustomFontID=1|PinPropagationDelay=0.000000E+000
|RECORD=2|OwnerIndex=795|OwnerPartId=1|PinConglomerate=58|PinLength=20|Location.X=700|Location.Y=370|Name=O\E\|Designator=6|PinName_PositionConglomerate=16|Name_CustomFontID=1|PinDesignator_PositionConglomerate=16|Designator_CustomFontID=1|PinPropagationDelay=0.000000E+000
|RECORD=2|OwnerIndex=795|OwnerPartId=1|Electrical=4|PinConglomerate=58|PinLength=20|Location.X=700|Location.Y=480|Name=NC1|Designator=10|PinName_PositionConglomerate=16|Name_CustomFontID=1|PinDesignator_PositionConglomerate=16|Designator_CustomFontID=1|PinPropagationDelay=0.000000E+000
|RECORD=2|OwnerIndex=795|OwnerPartId=1|Electrical=4|PinConglomerate=58|PinLength=20|Location.X=700|Location.Y=440|Name=NC2|Designator=8|PinName_PositionConglomerate=16|Name_CustomFontID=1|PinDesignator_PositionConglomerate=16|Designator_CustomFontID=1|PinPropagationDelay=0.000000E+000
|RECORD=2|OwnerIndex=795|OwnerPartId=1|Electrical=7|PinConglomerate=56|PinLength=20|Location.X=800|Location.Y=350|Name=GND|Designator=3|PinName_PositionConglomerate=16|Name_CustomFontID=1|PinDesignator_PositionConglomerate=16|Designator_CustomFontID=1|PinPropagationDelay=0.000000E+000
|RECORD=41|OwnerIndex=795|IndexInSheet=13|OwnerPartId=-1|Location.X=678|Location.Y=510|Color=8388608|FontID=1|IsHidden=T|Text=12|Name=Number of Pins
|RECORD=41|OwnerIndex=795|IndexInSheet=14|OwnerPartId=-1|Location.X=678|Location.Y=510|Color=8388608|FontID=1|IsHidden=T|Text=2|Name=Number of Circuits
|RECORD=41|OwnerIndex=795|IndexInSheet=15|OwnerPartId=-1|Location.X=678|Location.Y=510|Color=8388608|FontID=1|IsHidden=T|Text=-40°C|Name=Min Operating Temperature
|RECORD=41|OwnerIndex=795|IndexInSheet=16|OwnerPartId=-1|Location.X=678|Location.Y=510|Color=8388608|FontID=1|IsHidden=T|Text=Yes|Name=RoHS Compliant
|RECORD=41|OwnerIndex=795|IndexInSheet=17|OwnerPartId=-1|Location.X=678|Location.Y=510|Color=8388608|FontID=1|IsHidden=T|Text=1.2GHz|Name=-3db Bandwidth
|RECORD=41|OwnerIndex=795|IndexInSheet=18|OwnerPartId=-1|Location.X=678|Location.Y=510|Color=8388608|FontID=1|IsHidden=T|Text=125°C|Name=Max Operating Temperature
|RECORD=41|OwnerIndex=795|IndexInSheet=19|OwnerPartId=-1|Location.X=678|Location.Y=510|Color=8388608|FontID=1|IsHidden=T|Text=2|Name=Number of Channels
|RECORD=41|OwnerIndex=795|IndexInSheet=20|OwnerPartId=-1|Location.X=678|Location.Y=510|Color=8388608|FontID=1|IsHidden=T|Text=18R|Name=On-State Resistance
|RECORD=41|OwnerIndex=795|IndexInSheet=21|OwnerPartId=-1|Location.X=678|Location.Y=510|Color=8388608|FontID=1|IsHidden=T|Text=Tape and Reel|Name=Packaging
|RECORD=34|OwnerIndex=795|IndexInSheet=-1|OwnerPartId=-1|Location.X=700|Location.Y=510|Color=8388608|FontID=1|Text=U22|Name=Designator|ReadOnlyState=1
|RECORD=41|OwnerIndex=795|IndexInSheet=-1|OwnerPartId=1|Location.X=700|Location.Y=330|Color=8388608|FontID=1|Text=TMUX1072RUTR|Name=Comment
|RECORD=44|OwnerIndex=795
|RECORD=45|OwnerIndex=832|IndexInSheet=-1|UseComponentLibrary=T|ModelName=FP-RUT0012A-MFG|ModelType=PCBLIB|DatafileCount=1|ModelDatafileEntity0=FP-RUT0012A-MFG|ModelDatafileKind0=PCBLib|IsCurrent=T|DatalinksLocked=T|DatabaseDatalinksLocked=T
|RECORD=46|OwnerIndex=833
|RECORD=48|OwnerIndex=833
|RECORD=17|IndexInSheet=65|OwnerPartId=-1|Style=4|ShowNetName=T|Location.X=660|Location.Y=340|Orientation=3|Color=128|FontID=1|Text=GND
|RECORD=1|LibReference=b4654b650e69147ec39a6b967a45e02|ComponentDescription=General Purpose Ceramic Capacitor, 0402, 100nF, 10%, X7R, 15%, 25V|PartCount=2|DisplayModeCount=1|IndexInSheet=66|OwnerPartId=-1|Location.X=620|Location.Y=530|CurrentPartId=1|LibraryPath=*|SourceLibraryName=Altium Content Vault|TargetFileName=*|AreaColor=11599871|Color=128|PartIDLocked=T|DesignItemId=CMP-2008-02519-2|AllPinCount=2
|RECORD=2|OwnerIndex=837|OwnerPartId=1|Electrical=4|PinConglomerate=49|PinLength=7|Location.X=620|Location.Y=523|Name=1|Designator=1|PinPropagationDelay=0.000000E+000
|RECORD=2|OwnerIndex=837|OwnerPartId=1|Electrical=4|PinConglomerate=51|PinLength=6|Location.X=620|Location.Y=516|Name=2|Designator=2|PinPropagationDelay=0.000000E+000
|RECORD=13|OwnerIndex=837|IsNotAccesible=T|IndexInSheet=2|OwnerPartId=1|Location.X=630|Location.Y=523|Corner.X=610|Corner.Y=523|LineWidth=1|Color=16711680
|RECORD=13|OwnerIndex=837|IsNotAccesible=T|IndexInSheet=3|OwnerPartId=1|Location.X=630|Location.Y=517|Corner.X=610|Corner.Y=517|LineWidth=1|Color=16711680
|RECORD=13|OwnerIndex=837|IsNotAccesible=T|IndexInSheet=4|OwnerPartId=1|Location.X=620|Location.Y=523|Corner.X=620|Corner.Y=526|LineWidth=1|Color=16711680
|RECORD=13|OwnerIndex=837|IsNotAccesible=T|IndexInSheet=5|OwnerPartId=1|Location.X=620|Location.Y=516|Corner.X=620|Corner.Y=515|LineWidth=1|Color=16711680
|RECORD=41|OwnerIndex=837|IndexInSheet=6|OwnerPartId=-1|Location.X=609|Location.Y=532|Color=8388608|FontID=1|IsHidden=T|Text=1|Name=Package Quantity
|RECORD=41|OwnerIndex=837|IndexInSheet=7|OwnerPartId=-1|Location.X=609|Location.Y=532|Color=8388608|FontID=1|IsHidden=T|Text=100nF|Name=Capacitance
|RECORD=41|OwnerIndex=837|IndexInSheet=8|OwnerPartId=-1|Location.X=609|Location.Y=532|Color=8388608|FontID=1|IsHidden=T|Text=-55°C|Name=Min Operating Temperature
|RECORD=41|OwnerIndex=837|IndexInSheet=9|OwnerPartId=-1|Location.X=609|Location.Y=532|Color=8388608|FontID=1|IsHidden=T|Text=25V|Name=Voltage
|RECORD=41|OwnerIndex=837|IndexInSheet=10|OwnerPartId=-1|Location.X=609|Location.Y=532|Color=8388608|FontID=1|IsHidden=T|Text=25V|Name=Voltage Rating
|RECORD=41|OwnerIndex=837|IndexInSheet=11|OwnerPartId=-1|Location.X=609|Location.Y=532|Color=8388608|FontID=1|IsHidden=T|Text=Flat|Name=Construction
|RECORD=41|OwnerIndex=837|IndexInSheet=12|OwnerPartId=-1|Location.X=609|Location.Y=532|Color=8388608|FontID=1|IsHidden=T|Text=125°C|Name=Max Operating Temperature
|RECORD=41|OwnerIndex=837|IndexInSheet=13|OwnerPartId=-1|Location.X=609|Location.Y=532|Color=8388608|FontID=1|IsHidden=T|Text=No|Name=Radiation Hardening
|RECORD=41|OwnerIndex=837|IndexInSheet=14|OwnerPartId=-1|Location.X=609|Location.Y=532|Color=8388608|FontID=1|IsHidden=T|Text=0.5mm|Name=Depth
|RECORD=41|OwnerIndex=837|IndexInSheet=15|OwnerPartId=-1|Location.X=609|Location.Y=532|Color=8388608|FontID=1|IsHidden=T|Text=0.022inch|Name=Thickness
|RECORD=41|OwnerIndex=837|IndexInSheet=16|OwnerPartId=-1|Location.X=609|Location.Y=532|Color=8388608|FontID=1|IsHidden=T|Text=25V|Name=Voltage Rating (DC)
|RECORD=41|OwnerIndex=837|IndexInSheet=17|OwnerPartId=-1|Location.X=609|Location.Y=532|Color=8388608|FontID=1|IsHidden=T|Text=2|Name=Number of Pins
|RECORD=41|OwnerIndex=837|IndexInSheet=18|OwnerPartId=-1|Location.X=609|Location.Y=532|Color=8388608|FontID=1|IsHidden=T|Text=Lead Free|Name=Lead Free
|RECORD=41|OwnerIndex=837|IndexInSheet=19|OwnerPartId=-1|Location.X=609|Location.Y=532|Color=8388608|FontID=1|IsHidden=T|Text=-|Name=Series
|RECORD=41|OwnerIndex=837|IndexInSheet=20|OwnerPartId=-1|Location.X=609|Location.Y=532|Color=8388608|FontID=1|IsHidden=T|Text=No SVHC|Name=REACH SVHC
|RECORD=41|OwnerIndex=837|IndexInSheet=21|OwnerPartId=-1|Location.X=609|Location.Y=532|Color=8388608|FontID=1|IsHidden=T|Text=1mm|Name=Length
|RECORD=41|OwnerIndex=837|IndexInSheet=22|OwnerPartId=-1|Location.X=609|Location.Y=532|Color=8388608|FontID=1|IsHidden=T|Text=X7R|Name=Dielectric
|RECORD=41|OwnerIndex=837|IndexInSheet=23|OwnerPartId=-1|Location.X=609|Location.Y=532|Color=8388608|FontID=1|IsHidden=T|Text=Yes|Name=RoHS Compliant
|RECORD=41|OwnerIndex=837|IndexInSheet=24|OwnerPartId=-1|Location.X=609|Location.Y=532|Color=8388608|FontID=1|IsHidden=T|Text=Surface Mount|Name=Mount
|RECORD=41|OwnerIndex=837|IndexInSheet=25|OwnerPartId=-1|Location.X=609|Location.Y=532|Color=8388608|FontID=1|IsHidden=T|Text=Tape and Reel|Name=Packaging
|RECORD=41|OwnerIndex=837|IndexInSheet=26|OwnerPartId=-1|Location.X=609|Location.Y=532|Color=8388608|FontID=1|IsHidden=T|Text=0402|Name=Case/Package
|RECORD=41|OwnerIndex=837|IndexInSheet=27|OwnerPartId=-1|Location.X=609|Location.Y=532|Color=8388608|FontID=1|IsHidden=T|Text=0402|Name=Case Code (Imperial)
|RECORD=41|OwnerIndex=837|IndexInSheet=28|OwnerPartId=-1|Location.X=609|Location.Y=532|Color=8388608|FontID=1|IsHidden=T|Text=SMD/SMT|Name=Termination
|RECORD=41|OwnerIndex=837|IndexInSheet=29|OwnerPartId=-1|Location.X=609|Location.Y=532|Color=8388608|FontID=1|IsHidden=T|Text=0.02inch|Name=Width
|RECORD=41|OwnerIndex=837|IndexInSheet=30|OwnerPartId=-1|Location.X=609|Location.Y=532|Color=8388608|FontID=1|IsHidden=T|Text=1005|Name=Case Code (Metric)
|RECORD=41|OwnerIndex=837|IndexInSheet=31|OwnerPartId=-1|Location.X=609|Location.Y=532|Color=8388608|FontID=1|IsHidden=T|Text=10%|Name=Tolerance
|RECORD=34|OwnerIndex=837|IndexInSheet=-1|OwnerPartId=-1|Location.X=610|Location.Y=510|Orientation=1|Color=8388608|FontID=2|Text=C95|Name=Designator|ReadOnlyState=1
|RECORD=41|OwnerIndex=837|IndexInSheet=-1|OwnerPartId=1|Location.X=640|Location.Y=495|Orientation=1|Color=8388608|FontID=2|Text=0.1uF_25V_0402|Name=Comment
|RECORD=44|OwnerIndex=837
|RECORD=45|OwnerIndex=874|IndexInSheet=-1|UseComponentLibrary=T|ModelName=FP-0402-L_1_0_1-W_0_5_0_1-IPC_C|ModelType=PCBLIB|DatafileCount=1|ModelDatafileEntity0=FP-0402-L_1_0_1-W_0_5_0_1-IPC_C|ModelDatafileKind0=PCBLib|IsCurrent=T|DatalinksLocked=T|DatabaseDatalinksLocked=T
|RECORD=46|OwnerIndex=875
|RECORD=48|OwnerIndex=875
|RECORD=45|OwnerIndex=874|IndexInSheet=-1|UseComponentLibrary=T|ModelName=FP-0402-L_1_0_1-W_0_5_0_1-IPC_B|ModelType=PCBLIB|DatafileCount=1|ModelDatafileEntity0=FP-0402-L_1_0_1-W_0_5_0_1-IPC_B|ModelDatafileKind0=PCBLib|DatalinksLocked=T|DatabaseDatalinksLocked=T
|RECORD=46|OwnerIndex=878
|RECORD=48|OwnerIndex=878
|RECORD=45|OwnerIndex=874|IndexInSheet=-1|UseComponentLibrary=T|ModelName=FP-0402-L_1_0_1-W_0_5_0_1-MFG|ModelType=PCBLIB|DatafileCount=1|ModelDatafileEntity0=FP-0402-L_1_0_1-W_0_5_0_1-MFG|ModelDatafileKind0=PCBLib|DatalinksLocked=T|DatabaseDatalinksLocked=T
|RECORD=46|OwnerIndex=881
|RECORD=48|OwnerIndex=881
|RECORD=45|OwnerIndex=874|IndexInSheet=-1|UseComponentLibrary=T|ModelName=FP-0402-L_1_0_1-W_0_5_0_1-IPC_A|ModelType=PCBLIB|DatafileCount=1|ModelDatafileEntity0=FP-0402-L_1_0_1-W_0_5_0_1-IPC_A|ModelDatafileKind0=PCBLib|DatalinksLocked=T|DatabaseDatalinksLocked=T
|RECORD=46|OwnerIndex=884
|RECORD=48|OwnerIndex=884
|RECORD=17|IndexInSheet=67|OwnerPartId=-1|ShowNetName=T|Location.X=620|Location.Y=580|Orientation=1|Color=128|FontID=1|Text=+3.3V
|RECORD=17|IndexInSheet=68|OwnerPartId=-1|Style=4|ShowNetName=T|Location.X=620|Location.Y=500|Orientation=3|Color=128|FontID=1|Text=GND
|RECORD=4|IndexInSheet=69|OwnerPartId=-1|Location.X=680|Location.Y=640|Color=8388608|FontID=1|Text=Select GPS Uart, either FTDI or FPGA
|RECORD=17|IndexInSheet=70|OwnerPartId=-1|ShowNetName=T|Location.X=570|Location.Y=400|Orientation=2|Color=255|FontID=1|Text=DIP_SW_UART_SEL|IsCrossSheetConnector=T
|RECORD=17|IndexInSheet=71|OwnerPartId=-1|Style=4|ShowNetName=T|Location.X=830|Location.Y=340|Orientation=3|Color=128|FontID=1|Text=GND
|RECORD=1|LibReference=RES|PartCount=2|DisplayModeCount=2|IndexInSheet=72|OwnerPartId=-1|Location.X=550|Location.Y=490|CurrentPartId=1|SourceLibraryName=Altium Content Vault|TargetFileName=*|AreaColor=11599871|Color=128|PartIDLocked=F|DesignItemId=CMP-2002-08434-1|AllPinCount=2
|RECORD=2|OwnerIndex=892|OwnerPartId=1|OwnerPartDisplayMode=1|FormalType=1|Electrical=4|PinConglomerate=32|PinLength=10|Location.X=570|Location.Y=480|Name=2|Designator=2|PinPropagationDelay=0.000000E+000
|RECORD=2|OwnerIndex=892|OwnerPartId=1|OwnerPartDisplayMode=1|FormalType=1|Electrical=4|PinConglomerate=34|PinLength=10|Location.X=550|Location.Y=480|Name=1|Designator=1|PinPropagationDelay=0.000000E+000
|RECORD=14|OwnerIndex=892|IsNotAccesible=T|IndexInSheet=2|OwnerPartId=1|OwnerPartDisplayMode=1|Location.X=550|Location.Y=476|Corner.X=570|Corner.Y=484|LineWidth=1|Color=16711680|AreaColor=11599871
|RECORD=2|OwnerIndex=892|OwnerPartId=1|FormalType=1|Electrical=4|PinConglomerate=32|PinLength=10|Location.X=570|Location.Y=480|Name=2|Designator=2|PinPropagationDelay=0.000000E+000
|RECORD=2|OwnerIndex=892|OwnerPartId=1|FormalType=1|Electrical=4|PinConglomerate=34|PinLength=10|Location.X=550|Location.Y=480|Name=1|Designator=1|PinPropagationDelay=0.000000E+000
|RECORD=6|OwnerIndex=892|IsNotAccesible=T|IndexInSheet=5|OwnerPartId=1|LineWidth=1|Color=16711680|LocationCount=10|X1=570|Y1=480|X2=566|Y2=480|X3=565|Y3=478|X4=563|Y4=482|X5=561|Y5=478|X6=559|Y6=482|X7=557|Y7=478|X8=555|Y8=482|X9=554|Y9=480|X10=550|Y10=480
|RECORD=41|OwnerIndex=892|IndexInSheet=6|OwnerPartId=-1|Location.X=538|Location.Y=493|Color=8388608|FontID=1|IsHidden=T|Text=CRCW040227R0FKED|Name=Part Number
|RECORD=41|OwnerIndex=892|IndexInSheet=7|OwnerPartId=-1|Location.X=538|Location.Y=493|Color=8388608|FontID=1|IsHidden=T|Text=Vishay Dale|Name=Manufacturer
|RECORD=34|OwnerIndex=892|IndexInSheet=-1|OwnerPartId=-1|Location.X=530|Location.Y=480|Color=8388608|FontID=1|Text=R90|Name=Designator|ReadOnlyState=1
|RECORD=41|OwnerIndex=892|IndexInSheet=-1|OwnerPartId=-1|Location.X=550|Location.Y=480|Color=8388608|FontID=1|Text=27_1%_0402|Name=Comment
|RECORD=44|OwnerIndex=892
|RECORD=45|OwnerIndex=907|IndexInSheet=-1|Description=Chip Resistor, 2-Leads, Body 1.00x0.50mm, IPC Medium Density|UseComponentLibrary=T|ModelName=RESC1005X40X25NL05T05|ModelType=PCBLIB|DatafileCount=1|ModelDatafileEntity0=RESC1005X40X25NL05T05|ModelDatafileKind0=PCBLib|IsCurrent=T|DatalinksLocked=T|DatabaseDatalinksLocked=T
|RECORD=46|OwnerIndex=908
|RECORD=48|OwnerIndex=908
|RECORD=41|OwnerIndex=910|IndexInSheet=-1|OwnerPartId=-1|Color=8388608|FontID=1|IsHidden=T|Text=2D|Name=Available Preview Images
|RECORD=45|OwnerIndex=907|IndexInSheet=-1|Description=Chip Resistor, 2-Leads, Body 1.00x0.50mm, IPC High Density|UseComponentLibrary=T|ModelName=RESC1005X40X25LL05T05|ModelType=PCBLIB|DatafileCount=1|ModelDatafileEntity0=RESC1005X40X25LL05T05|ModelDatafileKind0=PCBLib|DatalinksLocked=T|DatabaseDatalinksLocked=T
|RECORD=46|OwnerIndex=912
|RECORD=48|OwnerIndex=912
|RECORD=41|OwnerIndex=914|IndexInSheet=-1|OwnerPartId=-1|Color=8388608|FontID=1|IsHidden=T|Text=2D|Name=Available Preview Images
|RECORD=45|OwnerIndex=907|IndexInSheet=-1|Description=Chip Resistor, 2-Leads, Body 1.00x0.50mm, IPC Low Density|UseComponentLibrary=T|ModelName=RESC1005X40X25ML05T05|ModelType=PCBLIB|DatafileCount=1|ModelDatafileEntity0=RESC1005X40X25ML05T05|ModelDatafileKind0=PCBLib|DatalinksLocked=T|DatabaseDatalinksLocked=T
|RECORD=46|OwnerIndex=916
|RECORD=48|OwnerIndex=916
|RECORD=41|OwnerIndex=918|IndexInSheet=-1|OwnerPartId=-1|Color=8388608|FontID=1|IsHidden=T|Text=2D|Name=Available Preview Images
|RECORD=1|LibReference=RES|PartCount=2|DisplayModeCount=2|IndexInSheet=73|OwnerPartId=-1|Location.X=550|Location.Y=450|CurrentPartId=1|SourceLibraryName=Altium Content Vault|TargetFileName=*|AreaColor=11599871|Color=128|PartIDLocked=F|DesignItemId=CMP-2002-08434-1|AllPinCount=2
|RECORD=2|OwnerIndex=920|OwnerPartId=1|OwnerPartDisplayMode=1|FormalType=1|Electrical=4|PinConglomerate=32|PinLength=10|Location.X=570|Location.Y=440|Name=2|Designator=2|PinPropagationDelay=0.000000E+000
|RECORD=2|OwnerIndex=920|OwnerPartId=1|OwnerPartDisplayMode=1|FormalType=1|Electrical=4|PinConglomerate=34|PinLength=10|Location.X=550|Location.Y=440|Name=1|Designator=1|PinPropagationDelay=0.000000E+000
|RECORD=14|OwnerIndex=920|IsNotAccesible=T|IndexInSheet=2|OwnerPartId=1|OwnerPartDisplayMode=1|Location.X=550|Location.Y=436|Corner.X=570|Corner.Y=444|LineWidth=1|Color=16711680|AreaColor=11599871
|RECORD=2|OwnerIndex=920|OwnerPartId=1|FormalType=1|Electrical=4|PinConglomerate=32|PinLength=10|Location.X=570|Location.Y=440|Name=2|Designator=2|PinPropagationDelay=0.000000E+000
|RECORD=2|OwnerIndex=920|OwnerPartId=1|FormalType=1|Electrical=4|PinConglomerate=34|PinLength=10|Location.X=550|Location.Y=440|Name=1|Designator=1|PinPropagationDelay=0.000000E+000
|RECORD=6|OwnerIndex=920|IsNotAccesible=T|IndexInSheet=5|OwnerPartId=1|LineWidth=1|Color=16711680|LocationCount=10|X1=570|Y1=440|X2=566|Y2=440|X3=565|Y3=438|X4=563|Y4=442|X5=561|Y5=438|X6=559|Y6=442|X7=557|Y7=438|X8=555|Y8=442|X9=554|Y9=440|X10=550|Y10=440
|RECORD=41|OwnerIndex=920|IndexInSheet=6|OwnerPartId=-1|Location.X=538|Location.Y=453|Color=8388608|FontID=1|IsHidden=T|Text=CRCW040227R0FKED|Name=Part Number
|RECORD=41|OwnerIndex=920|IndexInSheet=7|OwnerPartId=-1|Location.X=538|Location.Y=453|Color=8388608|FontID=1|IsHidden=T|Text=Vishay Dale|Name=Manufacturer
|RECORD=34|OwnerIndex=920|IndexInSheet=-1|OwnerPartId=-1|Location.X=530|Location.Y=440|Color=8388608|FontID=1|Text=R92|Name=Designator|ReadOnlyState=1
|RECORD=41|OwnerIndex=920|IndexInSheet=-1|OwnerPartId=-1|Location.X=550|Location.Y=440|Color=8388608|FontID=1|Text=27_1%_0402|Name=Comment
|RECORD=44|OwnerIndex=920
|RECORD=45|OwnerIndex=935|IndexInSheet=-1|Description=Chip Resistor, 2-Leads, Body 1.00x0.50mm, IPC Medium Density|UseComponentLibrary=T|ModelName=RESC1005X40X25NL05T05|ModelType=PCBLIB|DatafileCount=1|ModelDatafileEntity0=RESC1005X40X25NL05T05|ModelDatafileKind0=PCBLib|IsCurrent=T|DatalinksLocked=T|DatabaseDatalinksLocked=T
|RECORD=46|OwnerIndex=936
|RECORD=48|OwnerIndex=936
|RECORD=41|OwnerIndex=938|IndexInSheet=-1|OwnerPartId=-1|Color=8388608|FontID=1|IsHidden=T|Text=2D|Name=Available Preview Images
|RECORD=45|OwnerIndex=935|IndexInSheet=-1|Description=Chip Resistor, 2-Leads, Body 1.00x0.50mm, IPC High Density|UseComponentLibrary=T|ModelName=RESC1005X40X25LL05T05|ModelType=PCBLIB|DatafileCount=1|ModelDatafileEntity0=RESC1005X40X25LL05T05|ModelDatafileKind0=PCBLib|DatalinksLocked=T|DatabaseDatalinksLocked=T
|RECORD=46|OwnerIndex=940
|RECORD=48|OwnerIndex=940
|RECORD=41|OwnerIndex=942|IndexInSheet=-1|OwnerPartId=-1|Color=8388608|FontID=1|IsHidden=T|Text=2D|Name=Available Preview Images
|RECORD=45|OwnerIndex=935|IndexInSheet=-1|Description=Chip Resistor, 2-Leads, Body 1.00x0.50mm, IPC Low Density|UseComponentLibrary=T|ModelName=RESC1005X40X25ML05T05|ModelType=PCBLIB|DatafileCount=1|ModelDatafileEntity0=RESC1005X40X25ML05T05|ModelDatafileKind0=PCBLib|DatalinksLocked=T|DatabaseDatalinksLocked=T
|RECORD=46|OwnerIndex=944
|RECORD=48|OwnerIndex=944
|RECORD=41|OwnerIndex=946|IndexInSheet=-1|OwnerPartId=-1|Color=8388608|FontID=1|IsHidden=T|Text=2D|Name=Available Preview Images
|RECORD=17|IndexInSheet=74|OwnerPartId=-1|ShowNetName=T|Location.X=500|Location.Y=420|Orientation=2|Color=255|FontID=1|Text=GPS2_RX_FPGA|IsCrossSheetConnector=T
|RECORD=17|IndexInSheet=75|OwnerPartId=-1|ShowNetName=T|Location.X=500|Location.Y=460|Orientation=2|Color=255|FontID=1|Text=GPS2_TX_FPGA|IsCrossSheetConnector=T
|RECORD=17|IndexInSheet=76|OwnerPartId=-1|ShowNetName=T|Location.X=500|Location.Y=440|Orientation=2|Color=255|FontID=1|Text=FTDI_TX|IsCrossSheetConnector=T
|RECORD=17|IndexInSheet=77|OwnerPartId=-1|Style=1|ShowNetName=T|Location.X=500|Location.Y=480|Orientation=2|Color=255|FontID=1|Text=FTDI_RX|IsCrossSheetConnector=T
|RECORD=17|IndexInSheet=78|OwnerPartId=-1|Style=1|ShowNetName=T|Location.X=890|Location.Y=440|Color=255|FontID=1|Text=GPS2_RX|IsCrossSheetConnector=T
|RECORD=17|IndexInSheet=79|OwnerPartId=-1|ShowNetName=T|Location.X=890|Location.Y=480|Color=255|FontID=1|Text=GPS2_TX|IsCrossSheetConnector=T
|RECORD=27|IndexInSheet=80|OwnerPartId=-1|LineWidth=1|Color=8388608|LocationCount=3|X1=160|Y1=680|X2=180|Y2=680|X3=180|Y3=660
|RECORD=27|IndexInSheet=81|OwnerPartId=-1|LineWidth=1|Color=8388608|LocationCount=3|X1=160|Y1=700|X2=180|Y2=700|X3=180|Y3=680
|RECORD=27|IndexInSheet=82|OwnerPartId=-1|LineWidth=1|Color=8388608|LocationCount=3|X1=160|Y1=720|X2=180|Y2=720|X3=180|Y3=700
|RECORD=27|IndexInSheet=83|OwnerPartId=-1|LineWidth=1|Color=8388608|LocationCount=3|X1=160|Y1=740|X2=180|Y2=740|X3=180|Y3=720
|RECORD=27|IndexInSheet=84|OwnerPartId=-1|LineWidth=1|Color=8388608|LocationCount=3|X1=160|Y1=770|X2=180|Y2=770|X3=180|Y3=740
|RECORD=27|IndexInSheet=85|OwnerPartId=-1|LineWidth=1|Color=8388608|LocationCount=3|X1=220|Y1=750|X2=220|Y2=720|X3=180|Y3=720
|RECORD=27|IndexInSheet=86|OwnerPartId=-1|LineWidth=1|Color=8388608|LocationCount=2|X1=460|Y1=820|X2=570|Y2=820
|RECORD=27|IndexInSheet=87|OwnerPartId=-1|LineWidth=1|Color=8388608|LocationCount=2|X1=460|Y1=810|X2=570|Y2=810
|RECORD=27|IndexInSheet=88|OwnerPartId=-1|LineWidth=1|Color=8388608|LocationCount=3|X1=570|Y1=840|X2=550|Y2=840|X3=550|Y3=770
|RECORD=27|IndexInSheet=89|OwnerPartId=-1|LineWidth=1|Color=8388608|LocationCount=2|X1=740|Y1=770|X2=750|Y2=770
|RECORD=27|IndexInSheet=90|OwnerPartId=-1|LineWidth=1|Color=8388608|LocationCount=3|X1=420|Y1=790|X2=400|Y2=790|X3=400|Y3=850
|RECORD=27|IndexInSheet=91|OwnerPartId=-1|LineWidth=1|Color=8388608|LocationCount=2|X1=740|Y1=840|X2=770|Y2=840
|RECORD=27|IndexInSheet=92|OwnerPartId=-1|LineWidth=1|Color=8388608|LocationCount=2|X1=770|Y1=850|X2=740|Y2=850
|RECORD=27|IndexInSheet=93|OwnerPartId=-1|LineWidth=1|Color=8388608|LocationCount=2|X1=810|Y1=850|X2=870|Y2=850
|RECORD=27|IndexInSheet=94|OwnerPartId=-1|LineWidth=1|Color=8388608|LocationCount=2|X1=810|Y1=840|X2=870|Y2=840
|RECORD=27|IndexInSheet=95|OwnerPartId=-1|LineWidth=1|Color=8388608|LocationCount=3|X1=240|Y1=850|X2=240|Y2=770|X3=220|Y3=770
|RECORD=27|IndexInSheet=96|OwnerPartId=-1|LineWidth=1|Color=8388608|LocationCount=2|X1=260|Y1=740|X2=260|Y2=720
|RECORD=27|IndexInSheet=97|OwnerPartId=-1|LineWidth=1|Color=8388608|LocationCount=2|X1=260|Y1=810|X2=260|Y2=770
|RECORD=27|IndexInSheet=98|OwnerPartId=-1|LineWidth=1|Color=8388608|LocationCount=2|X1=300|Y1=740|X2=300|Y2=720
|RECORD=27|IndexInSheet=99|OwnerPartId=-1|LineWidth=1|Color=8388608|LocationCount=2|X1=300|Y1=830|X2=300|Y2=770
|RECORD=27|IndexInSheet=100|OwnerPartId=-1|LineWidth=1|Color=8388608|LocationCount=2|X1=340|Y1=770|X2=340|Y2=850
|RECORD=27|IndexInSheet=101|OwnerPartId=-1|LineWidth=1|Color=8388608|LocationCount=2|X1=380|Y1=770|X2=380|Y2=850
|RECORD=27|IndexInSheet=102|OwnerPartId=-1|LineWidth=1|Color=8388608|LocationCount=3|X1=380|Y1=750|X2=380|Y2=720|X3=340|Y3=720
|RECORD=27|IndexInSheet=103|OwnerPartId=-1|LineWidth=1|Color=8388608|LocationCount=3|X1=590|Y1=720|X2=590|Y2=750|X3=550|Y3=750
|RECORD=27|IndexInSheet=104|OwnerPartId=-1|LineWidth=1|Color=8388608|LocationCount=3|X1=590|Y1=700|X2=590|Y2=680|X3=550|Y3=680
|RECORD=27|IndexInSheet=105|OwnerPartId=-1|LineWidth=1|Color=8388608|LocationCount=4|X1=450|Y1=720|X2=450|Y2=690|X3=490|Y3=690|X4=490|Y4=660
|RECORD=27|IndexInSheet=106|OwnerPartId=-1|LineWidth=1|Color=8388608|LocationCount=3|X1=160|Y1=810|X2=260|Y2=810|X3=420|Y3=810
|RECORD=27|IndexInSheet=107|OwnerPartId=-1|LineWidth=1|Color=8388608|LocationCount=5|X1=160|Y1=830|X2=300|Y2=830|X3=390|Y3=830|X4=390|Y4=820|X5=420|Y5=820
|RECORD=27|IndexInSheet=108|OwnerPartId=-1|LineWidth=1|Color=8388608|LocationCount=3|X1=160|Y1=850|X2=240|Y2=850|X3=250|Y3=850
|RECORD=27|IndexInSheet=109|OwnerPartId=-1|LineWidth=1|Color=8388608|LocationCount=5|X1=220|Y1=720|X2=260|Y2=720|X3=300|Y3=720|X4=340|Y4=720|X5=340|Y5=750
|RECORD=27|IndexInSheet=110|OwnerPartId=-1|LineWidth=1|Color=8388608|LocationCount=5|X1=300|Y1=850|X2=340|Y2=850|X3=380|Y3=850|X4=400|Y4=850|X5=570|Y5=850
|RECORD=27|IndexInSheet=111|OwnerPartId=-1|LineWidth=1|Color=8388608|LocationCount=3|X1=460|Y1=790|X2=490|Y2=790|X3=570|Y3=790
|RECORD=27|IndexInSheet=112|OwnerPartId=-1|LineWidth=1|Color=8388608|LocationCount=4|X1=550|Y1=720|X2=550|Y2=750|X3=550|Y3=770|X4=570|Y4=770
|RECORD=27|IndexInSheet=113|OwnerPartId=-1|LineWidth=1|Color=8388608|LocationCount=4|X1=740|Y1=780|X2=750|Y2=780|X3=750|Y3=770|X4=750|Y4=750
|RECORD=27|IndexInSheet=114|OwnerPartId=-1|LineWidth=1|Color=8388608|LocationCount=3|X1=550|Y1=660|X2=550|Y2=680|X3=550|Y3=700
|RECORD=27|IndexInSheet=115|OwnerPartId=-1|LineWidth=1|Color=8388608|LocationCount=2|X1=130|Y1=450|X2=110|Y2=450
|RECORD=27|IndexInSheet=116|OwnerPartId=-1|LineWidth=1|Color=8388608|LocationCount=3|X1=210|Y1=470|X2=230|Y2=470|X3=290|Y3=470
|RECORD=27|IndexInSheet=117|OwnerPartId=-1|LineWidth=1|Color=8388608|LocationCount=3|X1=210|Y1=450|X2=270|Y2=450|X3=290|Y3=450
|RECORD=27|IndexInSheet=118|OwnerPartId=-1|LineWidth=1|Color=8388608|LocationCount=4|X1=130|Y1=470|X2=110|Y2=470|X3=110|Y3=450|X4=110|Y4=430
|RECORD=27|IndexInSheet=119|OwnerPartId=-1|LineWidth=1|Color=8388608|LocationCount=2|X1=230|Y1=520|X2=230|Y2=540
|RECORD=27|IndexInSheet=120|OwnerPartId=-1|LineWidth=1|Color=8388608|LocationCount=2|X1=230|Y1=470|X2=230|Y2=480
|RECORD=27|IndexInSheet=121|OwnerPartId=-1|LineWidth=1|Color=8388608|LocationCount=2|X1=270|Y1=520|X2=270|Y2=540
|RECORD=27|IndexInSheet=122|OwnerPartId=-1|LineWidth=1|Color=8388608|LocationCount=2|X1=270|Y1=450|X2=270|Y2=480
|RECORD=27|IndexInSheet=123|OwnerPartId=-1|LineWidth=1|Color=8388608|LocationCount=2|X1=680|Y1=350|X2=660|Y2=350
|RECORD=27|IndexInSheet=124|OwnerPartId=-1|LineWidth=1|Color=8388608|LocationCount=4|X1=620|Y1=560|X2=650|Y2=560|X3=650|Y3=500|X4=680|Y4=500
|RECORD=27|IndexInSheet=125|OwnerPartId=-1|LineWidth=1|Color=8388608|LocationCount=2|X1=620|Y1=500|X2=620|Y2=510
|RECORD=27|IndexInSheet=126|OwnerPartId=-1|LineWidth=1|Color=8388608|LocationCount=3|X1=680|Y1=390|X2=660|Y2=390|X3=660|Y3=400
|RECORD=27|IndexInSheet=127|OwnerPartId=-1|LineWidth=1|Color=8388608|LocationCount=3|X1=820|Y1=350|X2=830|Y2=350|X3=830|Y3=340
|RECORD=27|IndexInSheet=128|OwnerPartId=-1|LineWidth=1|Color=8388608|LocationCount=2|X1=580|Y1=480|X2=680|Y2=480
|RECORD=27|IndexInSheet=129|OwnerPartId=-1|LineWidth=1|Color=8388608|LocationCount=2|X1=580|Y1=440|X2=680|Y2=440
|RECORD=27|IndexInSheet=130|OwnerPartId=-1|LineWidth=1|Color=8388608|LocationCount=2|X1=540|Y1=440|X2=500|Y2=440
|RECORD=27|IndexInSheet=131|OwnerPartId=-1|LineWidth=1|Color=8388608|LocationCount=2|X1=500|Y1=480|X2=540|Y2=480
|RECORD=27|IndexInSheet=132|OwnerPartId=-1|LineWidth=1|Color=8388608|LocationCount=3|X1=890|Y1=440|X2=860|Y2=440|X3=820|Y3=440
|RECORD=27|IndexInSheet=133|OwnerPartId=-1|LineWidth=1|Color=8388608|LocationCount=3|X1=890|Y1=480|X2=840|Y2=480|X3=820|Y3=480
|RECORD=1|LibReference=RES|PartCount=2|DisplayModeCount=2|IndexInSheet=134|OwnerPartId=-1|Location.X=550|Location.Y=430|CurrentPartId=1|SourceLibraryName=Altium Content Vault|TargetFileName=*|AreaColor=11599871|Color=128|PartIDLocked=F|DesignItemId=CMP-2002-08434-1|AllPinCount=2
|RECORD=2|OwnerIndex=1008|OwnerPartId=1|OwnerPartDisplayMode=1|FormalType=1|Electrical=4|PinConglomerate=32|PinLength=10|Location.X=570|Location.Y=420|Name=2|Designator=2|PinPropagationDelay=0.000000E+000
|RECORD=2|OwnerIndex=1008|OwnerPartId=1|OwnerPartDisplayMode=1|FormalType=1|Electrical=4|PinConglomerate=34|PinLength=10|Location.X=550|Location.Y=420|Name=1|Designator=1|PinPropagationDelay=0.000000E+000
|RECORD=14|OwnerIndex=1008|IsNotAccesible=T|IndexInSheet=2|OwnerPartId=1|OwnerPartDisplayMode=1|Location.X=550|Location.Y=416|Corner.X=570|Corner.Y=424|LineWidth=1|Color=16711680|AreaColor=11599871
|RECORD=2|OwnerIndex=1008|OwnerPartId=1|FormalType=1|Electrical=4|PinConglomerate=32|PinLength=10|Location.X=570|Location.Y=420|Name=2|Designator=2|PinPropagationDelay=0.000000E+000
|RECORD=2|OwnerIndex=1008|OwnerPartId=1|FormalType=1|Electrical=4|PinConglomerate=34|PinLength=10|Location.X=550|Location.Y=420|Name=1|Designator=1|PinPropagationDelay=0.000000E+000
|RECORD=6|OwnerIndex=1008|IsNotAccesible=T|IndexInSheet=5|OwnerPartId=1|LineWidth=1|Color=16711680|LocationCount=10|X1=570|Y1=420|X2=566|Y2=420|X3=565|Y3=418|X4=563|Y4=422|X5=561|Y5=418|X6=559|Y6=422|X7=557|Y7=418|X8=555|Y8=422|X9=554|Y9=420|X10=550|Y10=420
|RECORD=41|OwnerIndex=1008|IndexInSheet=6|OwnerPartId=-1|Location.X=538|Location.Y=433|Color=8388608|FontID=1|IsHidden=T|Text=CRCW040227R0FKED|Name=Part Number
|RECORD=41|OwnerIndex=1008|IndexInSheet=7|OwnerPartId=-1|Location.X=538|Location.Y=433|Color=8388608|FontID=1|IsHidden=T|Text=Vishay Dale|Name=Manufacturer
|RECORD=34|OwnerIndex=1008|IndexInSheet=-1|OwnerPartId=-1|Location.X=530|Location.Y=420|Color=8388608|FontID=1|Text=R93|Name=Designator|ReadOnlyState=1
|RECORD=41|OwnerIndex=1008|IndexInSheet=-1|OwnerPartId=-1|Location.X=550|Location.Y=420|Color=8388608|FontID=1|Text=27_1%_0402|Name=Comment
|RECORD=44|OwnerIndex=1008
|RECORD=45|OwnerIndex=1023|IndexInSheet=-1|Description=Chip Resistor, 2-Leads, Body 1.00x0.50mm, IPC Medium Density|UseComponentLibrary=T|ModelName=RESC1005X40X25NL05T05|ModelType=PCBLIB|DatafileCount=1|ModelDatafileEntity0=RESC1005X40X25NL05T05|ModelDatafileKind0=PCBLib|IsCurrent=T|DatalinksLocked=T|DatabaseDatalinksLocked=T
|RECORD=46|OwnerIndex=1024
|RECORD=48|OwnerIndex=1024
|RECORD=41|OwnerIndex=1026|IndexInSheet=-1|OwnerPartId=-1|Color=8388608|FontID=1|IsHidden=T|Text=2D|Name=Available Preview Images
|RECORD=45|OwnerIndex=1023|IndexInSheet=-1|Description=Chip Resistor, 2-Leads, Body 1.00x0.50mm, IPC High Density|UseComponentLibrary=T|ModelName=RESC1005X40X25LL05T05|ModelType=PCBLIB|DatafileCount=1|ModelDatafileEntity0=RESC1005X40X25LL05T05|ModelDatafileKind0=PCBLib|DatalinksLocked=T|DatabaseDatalinksLocked=T
|RECORD=46|OwnerIndex=1028
|RECORD=48|OwnerIndex=1028
|RECORD=41|OwnerIndex=1030|IndexInSheet=-1|OwnerPartId=-1|Color=8388608|FontID=1|IsHidden=T|Text=2D|Name=Available Preview Images
|RECORD=45|OwnerIndex=1023|IndexInSheet=-1|Description=Chip Resistor, 2-Leads, Body 1.00x0.50mm, IPC Low Density|UseComponentLibrary=T|ModelName=RESC1005X40X25ML05T05|ModelType=PCBLIB|DatafileCount=1|ModelDatafileEntity0=RESC1005X40X25ML05T05|ModelDatafileKind0=PCBLib|DatalinksLocked=T|DatabaseDatalinksLocked=T
|RECORD=46|OwnerIndex=1032
|RECORD=48|OwnerIndex=1032
|RECORD=41|OwnerIndex=1034|IndexInSheet=-1|OwnerPartId=-1|Color=8388608|FontID=1|IsHidden=T|Text=2D|Name=Available Preview Images
|RECORD=27|IndexInSheet=135|OwnerPartId=-1|LineWidth=1|Color=8388608|LocationCount=2|X1=500|Y1=420|X2=540|Y2=420
|RECORD=27|IndexInSheet=136|OwnerPartId=-1|LineWidth=1|Color=8388608|LocationCount=2|X1=580|Y1=420|X2=680|Y2=420
|RECORD=1|LibReference=RES|PartCount=2|DisplayModeCount=2|IndexInSheet=137|OwnerPartId=-1|Location.X=550|Location.Y=470|CurrentPartId=1|SourceLibraryName=Altium Content Vault|TargetFileName=*|AreaColor=11599871|Color=128|PartIDLocked=F|DesignItemId=CMP-2002-08434-1|AllPinCount=2
|RECORD=2|OwnerIndex=1038|OwnerPartId=1|OwnerPartDisplayMode=1|FormalType=1|Electrical=4|PinConglomerate=32|PinLength=10|Location.X=570|Location.Y=460|Name=2|Designator=2|PinPropagationDelay=0.000000E+000
|RECORD=2|OwnerIndex=1038|OwnerPartId=1|OwnerPartDisplayMode=1|FormalType=1|Electrical=4|PinConglomerate=34|PinLength=10|Location.X=550|Location.Y=460|Name=1|Designator=1|PinPropagationDelay=0.000000E+000
|RECORD=14|OwnerIndex=1038|IsNotAccesible=T|IndexInSheet=2|OwnerPartId=1|OwnerPartDisplayMode=1|Location.X=550|Location.Y=456|Corner.X=570|Corner.Y=464|LineWidth=1|Color=16711680|AreaColor=11599871
|RECORD=2|OwnerIndex=1038|OwnerPartId=1|FormalType=1|Electrical=4|PinConglomerate=32|PinLength=10|Location.X=570|Location.Y=460|Name=2|Designator=2|PinPropagationDelay=0.000000E+000
|RECORD=2|OwnerIndex=1038|OwnerPartId=1|FormalType=1|Electrical=4|PinConglomerate=34|PinLength=10|Location.X=550|Location.Y=460|Name=1|Designator=1|PinPropagationDelay=0.000000E+000
|RECORD=6|OwnerIndex=1038|IsNotAccesible=T|IndexInSheet=5|OwnerPartId=1|LineWidth=1|Color=16711680|LocationCount=10|X1=570|Y1=460|X2=566|Y2=460|X3=565|Y3=458|X4=563|Y4=462|X5=561|Y5=458|X6=559|Y6=462|X7=557|Y7=458|X8=555|Y8=462|X9=554|Y9=460|X10=550|Y10=460
|RECORD=41|OwnerIndex=1038|IndexInSheet=6|OwnerPartId=-1|Location.X=538|Location.Y=473|Color=8388608|FontID=1|IsHidden=T|Text=CRCW040227R0FKED|Name=Part Number
|RECORD=41|OwnerIndex=1038|IndexInSheet=7|OwnerPartId=-1|Location.X=538|Location.Y=473|Color=8388608|FontID=1|IsHidden=T|Text=Vishay Dale|Name=Manufacturer
|RECORD=34|OwnerIndex=1038|IndexInSheet=-1|OwnerPartId=-1|Location.X=530|Location.Y=460|Color=8388608|FontID=1|Text=R91|Name=Designator|ReadOnlyState=1
|RECORD=41|OwnerIndex=1038|IndexInSheet=-1|OwnerPartId=-1|Location.X=550|Location.Y=460|Color=8388608|FontID=1|Text=27_1%_0402|Name=Comment
|RECORD=44|OwnerIndex=1038
|RECORD=45|OwnerIndex=1053|IndexInSheet=-1|Description=Chip Resistor, 2-Leads, Body 1.00x0.50mm, IPC Medium Density|UseComponentLibrary=T|ModelName=RESC1005X40X25NL05T05|ModelType=PCBLIB|DatafileCount=1|ModelDatafileEntity0=RESC1005X40X25NL05T05|ModelDatafileKind0=PCBLib|IsCurrent=T|DatalinksLocked=T|DatabaseDatalinksLocked=T
|RECORD=46|OwnerIndex=1054
|RECORD=48|OwnerIndex=1054
|RECORD=41|OwnerIndex=1056|IndexInSheet=-1|OwnerPartId=-1|Color=8388608|FontID=1|IsHidden=T|Text=2D|Name=Available Preview Images
|RECORD=45|OwnerIndex=1053|IndexInSheet=-1|Description=Chip Resistor, 2-Leads, Body 1.00x0.50mm, IPC High Density|UseComponentLibrary=T|ModelName=RESC1005X40X25LL05T05|ModelType=PCBLIB|DatafileCount=1|ModelDatafileEntity0=RESC1005X40X25LL05T05|ModelDatafileKind0=PCBLib|DatalinksLocked=T|DatabaseDatalinksLocked=T
|RECORD=46|OwnerIndex=1058
|RECORD=48|OwnerIndex=1058
|RECORD=41|OwnerIndex=1060|IndexInSheet=-1|OwnerPartId=-1|Color=8388608|FontID=1|IsHidden=T|Text=2D|Name=Available Preview Images
|RECORD=45|OwnerIndex=1053|IndexInSheet=-1|Description=Chip Resistor, 2-Leads, Body 1.00x0.50mm, IPC Low Density|UseComponentLibrary=T|ModelName=RESC1005X40X25ML05T05|ModelType=PCBLIB|DatafileCount=1|ModelDatafileEntity0=RESC1005X40X25ML05T05|ModelDatafileKind0=PCBLib|DatalinksLocked=T|DatabaseDatalinksLocked=T
|RECORD=46|OwnerIndex=1062
|RECORD=48|OwnerIndex=1062
|RECORD=41|OwnerIndex=1064|IndexInSheet=-1|OwnerPartId=-1|Color=8388608|FontID=1|IsHidden=T|Text=2D|Name=Available Preview Images
|RECORD=27|IndexInSheet=138|OwnerPartId=-1|LineWidth=1|Color=8388608|LocationCount=2|X1=580|Y1=460|X2=680|Y2=460
|RECORD=27|IndexInSheet=139|OwnerPartId=-1|LineWidth=1|Color=8388608|LocationCount=2|X1=540|Y1=460|X2=500|Y2=460
|RECORD=27|IndexInSheet=140|OwnerPartId=-1|LineWidth=1|Color=8388608|LocationCount=3|X1=570|Y1=400|X2=660|Y2=400|X3=680|Y3=400
|RECORD=27|IndexInSheet=141|OwnerPartId=-1|LineWidth=1|Color=8388608|LocationCount=4|X1=680|Y1=370|X2=660|Y2=370|X3=660|Y3=350|X4=660|Y4=340
|RECORD=27|IndexInSheet=142|OwnerPartId=-1|LineWidth=1|Color=8388608|LocationCount=3|X1=620|Y1=530|X2=620|Y2=560|X3=620|Y3=580
|RECORD=1|LibReference=12a319ab100cd6cfe745e35972674f5|ComponentDescription=IC SWITCH SPDT DUAL 12UQFN|PartCount=2|DisplayModeCount=1|IndexInSheet=143|OwnerPartId=-1|Location.X=1200|Location.Y=620|CurrentPartId=1|LibraryPath=*|SourceLibraryName=Altium Content Vault|TargetFileName=*|AreaColor=11599871|Color=128|PartIDLocked=T|DesignItemId=CMP-04892-000114-1|AllPinCount=12
|RECORD=14|OwnerIndex=1071|IsNotAccesible=T|OwnerPartId=1|Location.X=1220|Location.Y=460|Corner.X=1320|Corner.Y=630|LineWidth=1|Color=128|AreaColor=11599871|IsSolid=T
|RECORD=2|OwnerIndex=1071|OwnerPartId=1|Electrical=7|PinConglomerate=58|PinLength=20|Location.X=1220|Location.Y=620|Name=VCC|Designator=9|PinName_PositionConglomerate=16|Name_CustomFontID=1|PinDesignator_PositionConglomerate=16|Designator_CustomFontID=1|PinPropagationDelay=0.000000E+000
|RECORD=2|OwnerIndex=1071|OwnerPartId=1|PinConglomerate=58|PinLength=20|Location.X=1220|Location.Y=520|Name=SEL1|Designator=1|PinName_PositionConglomerate=16|Name_CustomFontID=1|PinDesignator_PositionConglomerate=16|Designator_CustomFontID=1|PinPropagationDelay=0.000000E+000
|RECORD=2|OwnerIndex=1071|OwnerPartId=1|PinConglomerate=58|PinLength=20|Location.X=1220|Location.Y=510|Name=SEL2|Designator=5|PinName_PositionConglomerate=16|Name_CustomFontID=1|PinDesignator_PositionConglomerate=16|Designator_CustomFontID=1|PinPropagationDelay=0.000000E+000
|RECORD=2|OwnerIndex=1071|OwnerPartId=1|Electrical=4|PinConglomerate=58|PinLength=20|Location.X=1220|Location.Y=580|Name=NO1|Designator=2|PinName_PositionConglomerate=16|Name_CustomFontID=1|PinDesignator_PositionConglomerate=16|Designator_CustomFontID=1|PinPropagationDelay=0.000000E+000
|RECORD=2|OwnerIndex=1071|OwnerPartId=1|Electrical=4|PinConglomerate=58|PinLength=20|Location.X=1220|Location.Y=540|Name=NO2|Designator=4|PinName_PositionConglomerate=16|Name_CustomFontID=1|PinDesignator_PositionConglomerate=16|Designator_CustomFontID=1|PinPropagationDelay=0.000000E+000
|RECORD=2|OwnerIndex=1071|OwnerPartId=1|Electrical=4|PinConglomerate=56|PinLength=20|Location.X=1320|Location.Y=600|Name=COM1|Designator=11|PinName_PositionConglomerate=16|Name_CustomFontID=1|PinDesignator_PositionConglomerate=16|Designator_CustomFontID=1|PinPropagationDelay=0.000000E+000
|RECORD=2|OwnerIndex=1071|OwnerPartId=1|Electrical=4|PinConglomerate=56|PinLength=20|Location.X=1320|Location.Y=560|Name=COM2|Designator=7|PinName_PositionConglomerate=16|Name_CustomFontID=1|PinDesignator_PositionConglomerate=16|Designator_CustomFontID=1|PinPropagationDelay=0.000000E+000
|RECORD=2|OwnerIndex=1071|OwnerPartId=1|Electrical=3|PinConglomerate=58|PinLength=20|Location.X=1220|Location.Y=470|Name=F\L\T\|Designator=12|PinName_PositionConglomerate=16|Name_CustomFontID=1|PinDesignator_PositionConglomerate=16|Designator_CustomFontID=1|PinPropagationDelay=0.000000E+000
|RECORD=2|OwnerIndex=1071|OwnerPartId=1|PinConglomerate=58|PinLength=20|Location.X=1220|Location.Y=490|Name=O\E\|Designator=6|PinName_PositionConglomerate=16|Name_CustomFontID=1|PinDesignator_PositionConglomerate=16|Designator_CustomFontID=1|PinPropagationDelay=0.000000E+000
|RECORD=2|OwnerIndex=1071|OwnerPartId=1|Electrical=4|PinConglomerate=58|PinLength=20|Location.X=1220|Location.Y=600|Name=NC1|Designator=10|PinName_PositionConglomerate=16|Name_CustomFontID=1|PinDesignator_PositionConglomerate=16|Designator_CustomFontID=1|PinPropagationDelay=0.000000E+000
|RECORD=2|OwnerIndex=1071|OwnerPartId=1|Electrical=4|PinConglomerate=58|PinLength=20|Location.X=1220|Location.Y=560|Name=NC2|Designator=8|PinName_PositionConglomerate=16|Name_CustomFontID=1|PinDesignator_PositionConglomerate=16|Designator_CustomFontID=1|PinPropagationDelay=0.000000E+000
|RECORD=2|OwnerIndex=1071|OwnerPartId=1|Electrical=7|PinConglomerate=56|PinLength=20|Location.X=1320|Location.Y=470|Name=GND|Designator=3|PinName_PositionConglomerate=16|Name_CustomFontID=1|PinDesignator_PositionConglomerate=16|Designator_CustomFontID=1|PinPropagationDelay=0.000000E+000
|RECORD=41|OwnerIndex=1071|IndexInSheet=13|OwnerPartId=-1|Location.X=1198|Location.Y=630|Color=8388608|FontID=1|IsHidden=T|Text=12|Name=Number of Pins
|RECORD=41|OwnerIndex=1071|IndexInSheet=14|OwnerPartId=-1|Location.X=1198|Location.Y=630|Color=8388608|FontID=1|IsHidden=T|Text=2|Name=Number of Circuits
|RECORD=41|OwnerIndex=1071|IndexInSheet=15|OwnerPartId=-1|Location.X=1198|Location.Y=630|Color=8388608|FontID=1|IsHidden=T|Text=-40°C|Name=Min Operating Temperature
|RECORD=41|OwnerIndex=1071|IndexInSheet=16|OwnerPartId=-1|Location.X=1198|Location.Y=630|Color=8388608|FontID=1|IsHidden=T|Text=Yes|Name=RoHS Compliant
|RECORD=41|OwnerIndex=1071|IndexInSheet=17|OwnerPartId=-1|Location.X=1198|Location.Y=630|Color=8388608|FontID=1|IsHidden=T|Text=1.2GHz|Name=-3db Bandwidth
|RECORD=41|OwnerIndex=1071|IndexInSheet=18|OwnerPartId=-1|Location.X=1198|Location.Y=630|Color=8388608|FontID=1|IsHidden=T|Text=125°C|Name=Max Operating Temperature
|RECORD=41|OwnerIndex=1071|IndexInSheet=19|OwnerPartId=-1|Location.X=1198|Location.Y=630|Color=8388608|FontID=1|IsHidden=T|Text=2|Name=Number of Channels
|RECORD=41|OwnerIndex=1071|IndexInSheet=20|OwnerPartId=-1|Location.X=1198|Location.Y=630|Color=8388608|FontID=1|IsHidden=T|Text=18R|Name=On-State Resistance
|RECORD=41|OwnerIndex=1071|IndexInSheet=21|OwnerPartId=-1|Location.X=1198|Location.Y=630|Color=8388608|FontID=1|IsHidden=T|Text=Tape and Reel|Name=Packaging
|RECORD=34|OwnerIndex=1071|IndexInSheet=-1|OwnerPartId=-1|Location.X=1220|Location.Y=630|Color=8388608|FontID=1|Text=U21|Name=Designator|ReadOnlyState=1
|RECORD=41|OwnerIndex=1071|IndexInSheet=-1|OwnerPartId=1|Location.X=1220|Location.Y=450|Color=8388608|FontID=1|Text=TMUX1072RUTR|Name=Comment
|RECORD=44|OwnerIndex=1071
|RECORD=45|OwnerIndex=1108|IndexInSheet=-1|UseComponentLibrary=T|ModelName=FP-RUT0012A-MFG|ModelType=PCBLIB|DatafileCount=1|ModelDatafileEntity0=FP-RUT0012A-MFG|ModelDatafileKind0=PCBLib|IsCurrent=T|DatalinksLocked=T|DatabaseDatalinksLocked=T
|RECORD=46|OwnerIndex=1109
|RECORD=48|OwnerIndex=1109
|RECORD=17|IndexInSheet=144|OwnerPartId=-1|Style=4|ShowNetName=T|Location.X=1180|Location.Y=460|Orientation=3|Color=128|FontID=1|Text=GND
|RECORD=1|LibReference=b4654b650e69147ec39a6b967a45e02|ComponentDescription=General Purpose Ceramic Capacitor, 0402, 100nF, 10%, X7R, 15%, 25V|PartCount=2|DisplayModeCount=1|IndexInSheet=145|OwnerPartId=-1|Location.X=1140|Location.Y=650|CurrentPartId=1|LibraryPath=*|SourceLibraryName=Altium Content Vault|TargetFileName=*|AreaColor=11599871|Color=128|PartIDLocked=T|DesignItemId=CMP-2008-02519-2|AllPinCount=2
|RECORD=2|OwnerIndex=1113|OwnerPartId=1|Electrical=4|PinConglomerate=49|PinLength=7|Location.X=1140|Location.Y=643|Name=1|Designator=1|PinPropagationDelay=0.000000E+000
|RECORD=2|OwnerIndex=1113|OwnerPartId=1|Electrical=4|PinConglomerate=51|PinLength=6|Location.X=1140|Location.Y=636|Name=2|Designator=2|PinPropagationDelay=0.000000E+000
|RECORD=13|OwnerIndex=1113|IsNotAccesible=T|IndexInSheet=2|OwnerPartId=1|Location.X=1150|Location.Y=643|Corner.X=1130|Corner.Y=643|LineWidth=1|Color=16711680
|RECORD=13|OwnerIndex=1113|IsNotAccesible=T|IndexInSheet=3|OwnerPartId=1|Location.X=1150|Location.Y=637|Corner.X=1130|Corner.Y=637|LineWidth=1|Color=16711680
|RECORD=13|OwnerIndex=1113|IsNotAccesible=T|IndexInSheet=4|OwnerPartId=1|Location.X=1140|Location.Y=643|Corner.X=1140|Corner.Y=646|LineWidth=1|Color=16711680
|RECORD=13|OwnerIndex=1113|IsNotAccesible=T|IndexInSheet=5|OwnerPartId=1|Location.X=1140|Location.Y=636|Corner.X=1140|Corner.Y=635|LineWidth=1|Color=16711680
|RECORD=41|OwnerIndex=1113|IndexInSheet=6|OwnerPartId=-1|Location.X=1129|Location.Y=652|Color=8388608|FontID=1|IsHidden=T|Text=1|Name=Package Quantity
|RECORD=41|OwnerIndex=1113|IndexInSheet=7|OwnerPartId=-1|Location.X=1129|Location.Y=652|Color=8388608|FontID=1|IsHidden=T|Text=100nF|Name=Capacitance
|RECORD=41|OwnerIndex=1113|IndexInSheet=8|OwnerPartId=-1|Location.X=1129|Location.Y=652|Color=8388608|FontID=1|IsHidden=T|Text=-55°C|Name=Min Operating Temperature
|RECORD=41|OwnerIndex=1113|IndexInSheet=9|OwnerPartId=-1|Location.X=1129|Location.Y=652|Color=8388608|FontID=1|IsHidden=T|Text=25V|Name=Voltage
|RECORD=41|OwnerIndex=1113|IndexInSheet=10|OwnerPartId=-1|Location.X=1129|Location.Y=652|Color=8388608|FontID=1|IsHidden=T|Text=25V|Name=Voltage Rating
|RECORD=41|OwnerIndex=1113|IndexInSheet=11|OwnerPartId=-1|Location.X=1129|Location.Y=652|Color=8388608|FontID=1|IsHidden=T|Text=Flat|Name=Construction
|RECORD=41|OwnerIndex=1113|IndexInSheet=12|OwnerPartId=-1|Location.X=1129|Location.Y=652|Color=8388608|FontID=1|IsHidden=T|Text=125°C|Name=Max Operating Temperature
|RECORD=41|OwnerIndex=1113|IndexInSheet=13|OwnerPartId=-1|Location.X=1129|Location.Y=652|Color=8388608|FontID=1|IsHidden=T|Text=No|Name=Radiation Hardening
|RECORD=41|OwnerIndex=1113|IndexInSheet=14|OwnerPartId=-1|Location.X=1129|Location.Y=652|Color=8388608|FontID=1|IsHidden=T|Text=0.5mm|Name=Depth
|RECORD=41|OwnerIndex=1113|IndexInSheet=15|OwnerPartId=-1|Location.X=1129|Location.Y=652|Color=8388608|FontID=1|IsHidden=T|Text=0.022inch|Name=Thickness
|RECORD=41|OwnerIndex=1113|IndexInSheet=16|OwnerPartId=-1|Location.X=1129|Location.Y=652|Color=8388608|FontID=1|IsHidden=T|Text=25V|Name=Voltage Rating (DC)
|RECORD=41|OwnerIndex=1113|IndexInSheet=17|OwnerPartId=-1|Location.X=1129|Location.Y=652|Color=8388608|FontID=1|IsHidden=T|Text=2|Name=Number of Pins
|RECORD=41|OwnerIndex=1113|IndexInSheet=18|OwnerPartId=-1|Location.X=1129|Location.Y=652|Color=8388608|FontID=1|IsHidden=T|Text=Lead Free|Name=Lead Free
|RECORD=41|OwnerIndex=1113|IndexInSheet=19|OwnerPartId=-1|Location.X=1129|Location.Y=652|Color=8388608|FontID=1|IsHidden=T|Text=-|Name=Series
|RECORD=41|OwnerIndex=1113|IndexInSheet=20|OwnerPartId=-1|Location.X=1129|Location.Y=652|Color=8388608|FontID=1|IsHidden=T|Text=No SVHC|Name=REACH SVHC
|RECORD=41|OwnerIndex=1113|IndexInSheet=21|OwnerPartId=-1|Location.X=1129|Location.Y=652|Color=8388608|FontID=1|IsHidden=T|Text=1mm|Name=Length
|RECORD=41|OwnerIndex=1113|IndexInSheet=22|OwnerPartId=-1|Location.X=1129|Location.Y=652|Color=8388608|FontID=1|IsHidden=T|Text=X7R|Name=Dielectric
|RECORD=41|OwnerIndex=1113|IndexInSheet=23|OwnerPartId=-1|Location.X=1129|Location.Y=652|Color=8388608|FontID=1|IsHidden=T|Text=Yes|Name=RoHS Compliant
|RECORD=41|OwnerIndex=1113|IndexInSheet=24|OwnerPartId=-1|Location.X=1129|Location.Y=652|Color=8388608|FontID=1|IsHidden=T|Text=Surface Mount|Name=Mount
|RECORD=41|OwnerIndex=1113|IndexInSheet=25|OwnerPartId=-1|Location.X=1129|Location.Y=652|Color=8388608|FontID=1|IsHidden=T|Text=Tape and Reel|Name=Packaging
|RECORD=41|OwnerIndex=1113|IndexInSheet=26|OwnerPartId=-1|Location.X=1129|Location.Y=652|Color=8388608|FontID=1|IsHidden=T|Text=0402|Name=Case/Package
|RECORD=41|OwnerIndex=1113|IndexInSheet=27|OwnerPartId=-1|Location.X=1129|Location.Y=652|Color=8388608|FontID=1|IsHidden=T|Text=0402|Name=Case Code (Imperial)
|RECORD=41|OwnerIndex=1113|IndexInSheet=28|OwnerPartId=-1|Location.X=1129|Location.Y=652|Color=8388608|FontID=1|IsHidden=T|Text=SMD/SMT|Name=Termination
|RECORD=41|OwnerIndex=1113|IndexInSheet=29|OwnerPartId=-1|Location.X=1129|Location.Y=652|Color=8388608|FontID=1|IsHidden=T|Text=0.02inch|Name=Width
|RECORD=41|OwnerIndex=1113|IndexInSheet=30|OwnerPartId=-1|Location.X=1129|Location.Y=652|Color=8388608|FontID=1|IsHidden=T|Text=1005|Name=Case Code (Metric)
|RECORD=41|OwnerIndex=1113|IndexInSheet=31|OwnerPartId=-1|Location.X=1129|Location.Y=652|Color=8388608|FontID=1|IsHidden=T|Text=10%|Name=Tolerance
|RECORD=34|OwnerIndex=1113|IndexInSheet=-1|OwnerPartId=-1|Location.X=1130|Location.Y=630|Orientation=1|Color=8388608|FontID=2|Text=C94|Name=Designator|ReadOnlyState=1
|RECORD=41|OwnerIndex=1113|IndexInSheet=-1|OwnerPartId=1|Location.X=1160|Location.Y=615|Orientation=1|Color=8388608|FontID=2|Text=0.1uF_25V_0402|Name=Comment
|RECORD=44|OwnerIndex=1113
|RECORD=45|OwnerIndex=1150|IndexInSheet=-1|UseComponentLibrary=T|ModelName=FP-0402-L_1_0_1-W_0_5_0_1-IPC_C|ModelType=PCBLIB|DatafileCount=1|ModelDatafileEntity0=FP-0402-L_1_0_1-W_0_5_0_1-IPC_C|ModelDatafileKind0=PCBLib|IsCurrent=T|DatalinksLocked=T|DatabaseDatalinksLocked=T
|RECORD=46|OwnerIndex=1151
|RECORD=48|OwnerIndex=1151
|RECORD=45|OwnerIndex=1150|IndexInSheet=-1|UseComponentLibrary=T|ModelName=FP-0402-L_1_0_1-W_0_5_0_1-IPC_B|ModelType=PCBLIB|DatafileCount=1|ModelDatafileEntity0=FP-0402-L_1_0_1-W_0_5_0_1-IPC_B|ModelDatafileKind0=PCBLib|DatalinksLocked=T|DatabaseDatalinksLocked=T
|RECORD=46|OwnerIndex=1154
|RECORD=48|OwnerIndex=1154
|RECORD=45|OwnerIndex=1150|IndexInSheet=-1|UseComponentLibrary=T|ModelName=FP-0402-L_1_0_1-W_0_5_0_1-MFG|ModelType=PCBLIB|DatafileCount=1|ModelDatafileEntity0=FP-0402-L_1_0_1-W_0_5_0_1-MFG|ModelDatafileKind0=PCBLib|DatalinksLocked=T|DatabaseDatalinksLocked=T
|RECORD=46|OwnerIndex=1157
|RECORD=48|OwnerIndex=1157
|RECORD=45|OwnerIndex=1150|IndexInSheet=-1|UseComponentLibrary=T|ModelName=FP-0402-L_1_0_1-W_0_5_0_1-IPC_A|ModelType=PCBLIB|DatafileCount=1|ModelDatafileEntity0=FP-0402-L_1_0_1-W_0_5_0_1-IPC_A|ModelDatafileKind0=PCBLib|DatalinksLocked=T|DatabaseDatalinksLocked=T
|RECORD=46|OwnerIndex=1160
|RECORD=48|OwnerIndex=1160
|RECORD=17|IndexInSheet=146|OwnerPartId=-1|ShowNetName=T|Location.X=1140|Location.Y=700|Orientation=1|Color=128|FontID=1|Text=+3.3V
|RECORD=17|IndexInSheet=147|OwnerPartId=-1|Style=4|ShowNetName=T|Location.X=1140|Location.Y=620|Orientation=3|Color=128|FontID=1|Text=GND
|RECORD=4|IndexInSheet=148|OwnerPartId=-1|Location.X=1210|Location.Y=680|Color=8388608|FontID=1|Text=Connect FTDI to FPGA otherwise
|RECORD=17|IndexInSheet=149|OwnerPartId=-1|ShowNetName=T|Location.X=1090|Location.Y=520|Orientation=2|Color=255|FontID=1|Text=DIP_SW_UART_SEL|IsCrossSheetConnector=T
|RECORD=17|IndexInSheet=150|OwnerPartId=-1|Style=4|ShowNetName=T|Location.X=1350|Location.Y=460|Orientation=3|Color=128|FontID=1|Text=GND
|RECORD=1|LibReference=RES|PartCount=2|DisplayModeCount=2|IndexInSheet=151|OwnerPartId=-1|Location.X=1070|Location.Y=610|CurrentPartId=1|SourceLibraryName=Altium Content Vault|TargetFileName=*|AreaColor=11599871|Color=128|PartIDLocked=F|DesignItemId=CMP-2002-08434-1|AllPinCount=2
|RECORD=2|OwnerIndex=1168|OwnerPartId=1|OwnerPartDisplayMode=1|FormalType=1|Electrical=4|PinConglomerate=32|PinLength=10|Location.X=1090|Location.Y=600|Name=2|Designator=2|PinPropagationDelay=0.000000E+000
|RECORD=2|OwnerIndex=1168|OwnerPartId=1|OwnerPartDisplayMode=1|FormalType=1|Electrical=4|PinConglomerate=34|PinLength=10|Location.X=1070|Location.Y=600|Name=1|Designator=1|PinPropagationDelay=0.000000E+000
|RECORD=14|OwnerIndex=1168|IsNotAccesible=T|IndexInSheet=2|OwnerPartId=1|OwnerPartDisplayMode=1|Location.X=1070|Location.Y=596|Corner.X=1090|Corner.Y=604|LineWidth=1|Color=16711680|AreaColor=11599871
|RECORD=2|OwnerIndex=1168|OwnerPartId=1|FormalType=1|Electrical=4|PinConglomerate=32|PinLength=10|Location.X=1090|Location.Y=600|Name=2|Designator=2|PinPropagationDelay=0.000000E+000
|RECORD=2|OwnerIndex=1168|OwnerPartId=1|FormalType=1|Electrical=4|PinConglomerate=34|PinLength=10|Location.X=1070|Location.Y=600|Name=1|Designator=1|PinPropagationDelay=0.000000E+000
|RECORD=6|OwnerIndex=1168|IsNotAccesible=T|IndexInSheet=5|OwnerPartId=1|LineWidth=1|Color=16711680|LocationCount=10|X1=1090|Y1=600|X2=1086|Y2=600|X3=1085|Y3=598|X4=1083|Y4=602|X5=1081|Y5=598|X6=1079|Y6=602|X7=1077|Y7=598|X8=1075|Y8=602|X9=1074|Y9=600|X10=1070|Y10=600
|RECORD=41|OwnerIndex=1168|IndexInSheet=6|OwnerPartId=-1|Location.X=1058|Location.Y=613|Color=8388608|FontID=1|IsHidden=T|Text=CRCW040227R0FKED|Name=Part Number
|RECORD=41|OwnerIndex=1168|IndexInSheet=7|OwnerPartId=-1|Location.X=1058|Location.Y=613|Color=8388608|FontID=1|IsHidden=T|Text=Vishay Dale|Name=Manufacturer
|RECORD=34|OwnerIndex=1168|IndexInSheet=-1|OwnerPartId=-1|Location.X=1050|Location.Y=600|Color=8388608|FontID=1|Text=R84|Name=Designator|ReadOnlyState=1
|RECORD=41|OwnerIndex=1168|IndexInSheet=-1|OwnerPartId=-1|Location.X=1070|Location.Y=600|Color=8388608|FontID=1|Text=27_1%_0402|Name=Comment
|RECORD=44|OwnerIndex=1168
|RECORD=45|OwnerIndex=1183|IndexInSheet=-1|Description=Chip Resistor, 2-Leads, Body 1.00x0.50mm, IPC Medium Density|UseComponentLibrary=T|ModelName=RESC1005X40X25NL05T05|ModelType=PCBLIB|DatafileCount=1|ModelDatafileEntity0=RESC1005X40X25NL05T05|ModelDatafileKind0=PCBLib|IsCurrent=T|DatalinksLocked=T|DatabaseDatalinksLocked=T
|RECORD=46|OwnerIndex=1184
|RECORD=48|OwnerIndex=1184
|RECORD=41|OwnerIndex=1186|IndexInSheet=-1|OwnerPartId=-1|Color=8388608|FontID=1|IsHidden=T|Text=2D|Name=Available Preview Images
|RECORD=45|OwnerIndex=1183|IndexInSheet=-1|Description=Chip Resistor, 2-Leads, Body 1.00x0.50mm, IPC High Density|UseComponentLibrary=T|ModelName=RESC1005X40X25LL05T05|ModelType=PCBLIB|DatafileCount=1|ModelDatafileEntity0=RESC1005X40X25LL05T05|ModelDatafileKind0=PCBLib|DatalinksLocked=T|DatabaseDatalinksLocked=T
|RECORD=46|OwnerIndex=1188
|RECORD=48|OwnerIndex=1188
|RECORD=41|OwnerIndex=1190|IndexInSheet=-1|OwnerPartId=-1|Color=8388608|FontID=1|IsHidden=T|Text=2D|Name=Available Preview Images
|RECORD=45|OwnerIndex=1183|IndexInSheet=-1|Description=Chip Resistor, 2-Leads, Body 1.00x0.50mm, IPC Low Density|UseComponentLibrary=T|ModelName=RESC1005X40X25ML05T05|ModelType=PCBLIB|DatafileCount=1|ModelDatafileEntity0=RESC1005X40X25ML05T05|ModelDatafileKind0=PCBLib|DatalinksLocked=T|DatabaseDatalinksLocked=T
|RECORD=46|OwnerIndex=1192
|RECORD=48|OwnerIndex=1192
|RECORD=41|OwnerIndex=1194|IndexInSheet=-1|OwnerPartId=-1|Color=8388608|FontID=1|IsHidden=T|Text=2D|Name=Available Preview Images
|RECORD=1|LibReference=RES|PartCount=2|DisplayModeCount=2|IndexInSheet=152|OwnerPartId=-1|Location.X=1070|Location.Y=570|CurrentPartId=1|SourceLibraryName=Altium Content Vault|TargetFileName=*|AreaColor=11599871|Color=128|PartIDLocked=F|DesignItemId=CMP-2002-08434-1|AllPinCount=2
|RECORD=2|OwnerIndex=1196|OwnerPartId=1|OwnerPartDisplayMode=1|FormalType=1|Electrical=4|PinConglomerate=32|PinLength=10|Location.X=1090|Location.Y=560|Name=2|Designator=2|PinPropagationDelay=0.000000E+000
|RECORD=2|OwnerIndex=1196|OwnerPartId=1|OwnerPartDisplayMode=1|FormalType=1|Electrical=4|PinConglomerate=34|PinLength=10|Location.X=1070|Location.Y=560|Name=1|Designator=1|PinPropagationDelay=0.000000E+000
|RECORD=14|OwnerIndex=1196|IsNotAccesible=T|IndexInSheet=2|OwnerPartId=1|OwnerPartDisplayMode=1|Location.X=1070|Location.Y=556|Corner.X=1090|Corner.Y=564|LineWidth=1|Color=16711680|AreaColor=11599871
|RECORD=2|OwnerIndex=1196|OwnerPartId=1|FormalType=1|Electrical=4|PinConglomerate=32|PinLength=10|Location.X=1090|Location.Y=560|Name=2|Designator=2|PinPropagationDelay=0.000000E+000
|RECORD=2|OwnerIndex=1196|OwnerPartId=1|FormalType=1|Electrical=4|PinConglomerate=34|PinLength=10|Location.X=1070|Location.Y=560|Name=1|Designator=1|PinPropagationDelay=0.000000E+000
|RECORD=6|OwnerIndex=1196|IsNotAccesible=T|IndexInSheet=5|OwnerPartId=1|LineWidth=1|Color=16711680|LocationCount=10|X1=1090|Y1=560|X2=1086|Y2=560|X3=1085|Y3=558|X4=1083|Y4=562|X5=1081|Y5=558|X6=1079|Y6=562|X7=1077|Y7=558|X8=1075|Y8=562|X9=1074|Y9=560|X10=1070|Y10=560
|RECORD=41|OwnerIndex=1196|IndexInSheet=6|OwnerPartId=-1|Location.X=1058|Location.Y=573|Color=8388608|FontID=1|IsHidden=T|Text=CRCW040227R0FKED|Name=Part Number
|RECORD=41|OwnerIndex=1196|IndexInSheet=7|OwnerPartId=-1|Location.X=1058|Location.Y=573|Color=8388608|FontID=1|IsHidden=T|Text=Vishay Dale|Name=Manufacturer
|RECORD=34|OwnerIndex=1196|IndexInSheet=-1|OwnerPartId=-1|Location.X=1050|Location.Y=560|Color=8388608|FontID=1|Text=R86|Name=Designator|ReadOnlyState=1
|RECORD=41|OwnerIndex=1196|IndexInSheet=-1|OwnerPartId=-1|Location.X=1070|Location.Y=560|Color=8388608|FontID=1|Text=27_1%_0402|Name=Comment
|RECORD=44|OwnerIndex=1196
|RECORD=45|OwnerIndex=1211|IndexInSheet=-1|Description=Chip Resistor, 2-Leads, Body 1.00x0.50mm, IPC Medium Density|UseComponentLibrary=T|ModelName=RESC1005X40X25NL05T05|ModelType=PCBLIB|DatafileCount=1|ModelDatafileEntity0=RESC1005X40X25NL05T05|ModelDatafileKind0=PCBLib|IsCurrent=T|DatalinksLocked=T|DatabaseDatalinksLocked=T
|RECORD=46|OwnerIndex=1212
|RECORD=48|OwnerIndex=1212
|RECORD=41|OwnerIndex=1214|IndexInSheet=-1|OwnerPartId=-1|Color=8388608|FontID=1|IsHidden=T|Text=2D|Name=Available Preview Images
|RECORD=45|OwnerIndex=1211|IndexInSheet=-1|Description=Chip Resistor, 2-Leads, Body 1.00x0.50mm, IPC High Density|UseComponentLibrary=T|ModelName=RESC1005X40X25LL05T05|ModelType=PCBLIB|DatafileCount=1|ModelDatafileEntity0=RESC1005X40X25LL05T05|ModelDatafileKind0=PCBLib|DatalinksLocked=T|DatabaseDatalinksLocked=T
|RECORD=46|OwnerIndex=1216
|RECORD=48|OwnerIndex=1216
|RECORD=41|OwnerIndex=1218|IndexInSheet=-1|OwnerPartId=-1|Color=8388608|FontID=1|IsHidden=T|Text=2D|Name=Available Preview Images
|RECORD=45|OwnerIndex=1211|IndexInSheet=-1|Description=Chip Resistor, 2-Leads, Body 1.00x0.50mm, IPC Low Density|UseComponentLibrary=T|ModelName=RESC1005X40X25ML05T05|ModelType=PCBLIB|DatafileCount=1|ModelDatafileEntity0=RESC1005X40X25ML05T05|ModelDatafileKind0=PCBLib|DatalinksLocked=T|DatabaseDatalinksLocked=T
|RECORD=46|OwnerIndex=1220
|RECORD=48|OwnerIndex=1220
|RECORD=41|OwnerIndex=1222|IndexInSheet=-1|OwnerPartId=-1|Color=8388608|FontID=1|IsHidden=T|Text=2D|Name=Available Preview Images
|RECORD=27|IndexInSheet=153|OwnerPartId=-1|LineWidth=1|Color=8388608|LocationCount=2|X1=1200|Y1=470|X2=1180|Y2=470
|RECORD=27|IndexInSheet=154|OwnerPartId=-1|LineWidth=1|Color=8388608|LocationCount=4|X1=1140|Y1=680|X2=1170|Y2=680|X3=1170|Y3=620|X4=1200|Y4=620
|RECORD=27|IndexInSheet=155|OwnerPartId=-1|LineWidth=1|Color=8388608|LocationCount=2|X1=1140|Y1=620|X2=1140|Y2=630
|RECORD=27|IndexInSheet=156|OwnerPartId=-1|LineWidth=1|Color=8388608|LocationCount=3|X1=1200|Y1=510|X2=1180|Y2=510|X3=1180|Y3=520
|RECORD=27|IndexInSheet=157|OwnerPartId=-1|LineWidth=1|Color=8388608|LocationCount=3|X1=1340|Y1=470|X2=1350|Y2=470|X3=1350|Y3=460
|RECORD=27|IndexInSheet=158|OwnerPartId=-1|LineWidth=1|Color=8388608|LocationCount=2|X1=1100|Y1=600|X2=1200|Y2=600
|RECORD=27|IndexInSheet=159|OwnerPartId=-1|LineWidth=1|Color=8388608|LocationCount=2|X1=1100|Y1=560|X2=1200|Y2=560
|RECORD=1|LibReference=RES|PartCount=2|DisplayModeCount=2|IndexInSheet=160|OwnerPartId=-1|Location.X=1070|Location.Y=550|CurrentPartId=1|SourceLibraryName=Altium Content Vault|TargetFileName=*|AreaColor=11599871|Color=128|PartIDLocked=F|DesignItemId=CMP-2002-08434-1|AllPinCount=2
|RECORD=2|OwnerIndex=1231|OwnerPartId=1|OwnerPartDisplayMode=1|FormalType=1|Electrical=4|PinConglomerate=32|PinLength=10|Location.X=1090|Location.Y=540|Name=2|Designator=2|PinPropagationDelay=0.000000E+000
|RECORD=2|OwnerIndex=1231|OwnerPartId=1|OwnerPartDisplayMode=1|FormalType=1|Electrical=4|PinConglomerate=34|PinLength=10|Location.X=1070|Location.Y=540|Name=1|Designator=1|PinPropagationDelay=0.000000E+000
|RECORD=14|OwnerIndex=1231|IsNotAccesible=T|IndexInSheet=2|OwnerPartId=1|OwnerPartDisplayMode=1|Location.X=1070|Location.Y=536|Corner.X=1090|Corner.Y=544|LineWidth=1|Color=16711680|AreaColor=11599871
|RECORD=2|OwnerIndex=1231|OwnerPartId=1|FormalType=1|Electrical=4|PinConglomerate=32|PinLength=10|Location.X=1090|Location.Y=540|Name=2|Designator=2|PinPropagationDelay=0.000000E+000
|RECORD=2|OwnerIndex=1231|OwnerPartId=1|FormalType=1|Electrical=4|PinConglomerate=34|PinLength=10|Location.X=1070|Location.Y=540|Name=1|Designator=1|PinPropagationDelay=0.000000E+000
|RECORD=6|OwnerIndex=1231|IsNotAccesible=T|IndexInSheet=5|OwnerPartId=1|LineWidth=1|Color=16711680|LocationCount=10|X1=1090|Y1=540|X2=1086|Y2=540|X3=1085|Y3=538|X4=1083|Y4=542|X5=1081|Y5=538|X6=1079|Y6=542|X7=1077|Y7=538|X8=1075|Y8=542|X9=1074|Y9=540|X10=1070|Y10=540
|RECORD=41|OwnerIndex=1231|IndexInSheet=6|OwnerPartId=-1|Location.X=1058|Location.Y=553|Color=8388608|FontID=1|IsHidden=T|Text=CRCW040227R0FKED|Name=Part Number
|RECORD=41|OwnerIndex=1231|IndexInSheet=7|OwnerPartId=-1|Location.X=1058|Location.Y=553|Color=8388608|FontID=1|IsHidden=T|Text=Vishay Dale|Name=Manufacturer
|RECORD=34|OwnerIndex=1231|IndexInSheet=-1|OwnerPartId=-1|Location.X=1050|Location.Y=540|Color=8388608|FontID=1|Text=R87|Name=Designator|ReadOnlyState=1
|RECORD=41|OwnerIndex=1231|IndexInSheet=-1|OwnerPartId=-1|Location.X=1070|Location.Y=540|Color=8388608|FontID=1|Text=27_1%_0402|Name=Comment
|RECORD=44|OwnerIndex=1231
|RECORD=45|OwnerIndex=1246|IndexInSheet=-1|Description=Chip Resistor, 2-Leads, Body 1.00x0.50mm, IPC Medium Density|UseComponentLibrary=T|ModelName=RESC1005X40X25NL05T05|ModelType=PCBLIB|DatafileCount=1|ModelDatafileEntity0=RESC1005X40X25NL05T05|ModelDatafileKind0=PCBLib|IsCurrent=T|DatalinksLocked=T|DatabaseDatalinksLocked=T
|RECORD=46|OwnerIndex=1247
|RECORD=48|OwnerIndex=1247
|RECORD=41|OwnerIndex=1249|IndexInSheet=-1|OwnerPartId=-1|Color=8388608|FontID=1|IsHidden=T|Text=2D|Name=Available Preview Images
|RECORD=45|OwnerIndex=1246|IndexInSheet=-1|Description=Chip Resistor, 2-Leads, Body 1.00x0.50mm, IPC High Density|UseComponentLibrary=T|ModelName=RESC1005X40X25LL05T05|ModelType=PCBLIB|DatafileCount=1|ModelDatafileEntity0=RESC1005X40X25LL05T05|ModelDatafileKind0=PCBLib|DatalinksLocked=T|DatabaseDatalinksLocked=T
|RECORD=46|OwnerIndex=1251
|RECORD=48|OwnerIndex=1251
|RECORD=41|OwnerIndex=1253|IndexInSheet=-1|OwnerPartId=-1|Color=8388608|FontID=1|IsHidden=T|Text=2D|Name=Available Preview Images
|RECORD=45|OwnerIndex=1246|IndexInSheet=-1|Description=Chip Resistor, 2-Leads, Body 1.00x0.50mm, IPC Low Density|UseComponentLibrary=T|ModelName=RESC1005X40X25ML05T05|ModelType=PCBLIB|DatafileCount=1|ModelDatafileEntity0=RESC1005X40X25ML05T05|ModelDatafileKind0=PCBLib|DatalinksLocked=T|DatabaseDatalinksLocked=T
|RECORD=46|OwnerIndex=1255
|RECORD=48|OwnerIndex=1255
|RECORD=41|OwnerIndex=1257|IndexInSheet=-1|OwnerPartId=-1|Color=8388608|FontID=1|IsHidden=T|Text=2D|Name=Available Preview Images
|RECORD=27|IndexInSheet=161|OwnerPartId=-1|LineWidth=1|Color=8388608|LocationCount=2|X1=1100|Y1=540|X2=1200|Y2=540
|RECORD=1|LibReference=RES|PartCount=2|DisplayModeCount=2|IndexInSheet=162|OwnerPartId=-1|Location.X=1070|Location.Y=590|CurrentPartId=1|SourceLibraryName=Altium Content Vault|TargetFileName=*|AreaColor=11599871|Color=128|PartIDLocked=F|DesignItemId=CMP-2002-08434-1|AllPinCount=2
|RECORD=2|OwnerIndex=1260|OwnerPartId=1|OwnerPartDisplayMode=1|FormalType=1|Electrical=4|PinConglomerate=32|PinLength=10|Location.X=1090|Location.Y=580|Name=2|Designator=2|PinPropagationDelay=0.000000E+000
|RECORD=2|OwnerIndex=1260|OwnerPartId=1|OwnerPartDisplayMode=1|FormalType=1|Electrical=4|PinConglomerate=34|PinLength=10|Location.X=1070|Location.Y=580|Name=1|Designator=1|PinPropagationDelay=0.000000E+000
|RECORD=14|OwnerIndex=1260|IsNotAccesible=T|IndexInSheet=2|OwnerPartId=1|OwnerPartDisplayMode=1|Location.X=1070|Location.Y=576|Corner.X=1090|Corner.Y=584|LineWidth=1|Color=16711680|AreaColor=11599871
|RECORD=2|OwnerIndex=1260|OwnerPartId=1|FormalType=1|Electrical=4|PinConglomerate=32|PinLength=10|Location.X=1090|Location.Y=580|Name=2|Designator=2|PinPropagationDelay=0.000000E+000
|RECORD=2|OwnerIndex=1260|OwnerPartId=1|FormalType=1|Electrical=4|PinConglomerate=34|PinLength=10|Location.X=1070|Location.Y=580|Name=1|Designator=1|PinPropagationDelay=0.000000E+000
|RECORD=6|OwnerIndex=1260|IsNotAccesible=T|IndexInSheet=5|OwnerPartId=1|LineWidth=1|Color=16711680|LocationCount=10|X1=1090|Y1=580|X2=1086|Y2=580|X3=1085|Y3=578|X4=1083|Y4=582|X5=1081|Y5=578|X6=1079|Y6=582|X7=1077|Y7=578|X8=1075|Y8=582|X9=1074|Y9=580|X10=1070|Y10=580
|RECORD=41|OwnerIndex=1260|IndexInSheet=6|OwnerPartId=-1|Location.X=1058|Location.Y=593|Color=8388608|FontID=1|IsHidden=T|Text=CRCW040227R0FKED|Name=Part Number
|RECORD=41|OwnerIndex=1260|IndexInSheet=7|OwnerPartId=-1|Location.X=1058|Location.Y=593|Color=8388608|FontID=1|IsHidden=T|Text=Vishay Dale|Name=Manufacturer
|RECORD=34|OwnerIndex=1260|IndexInSheet=-1|OwnerPartId=-1|Location.X=1050|Location.Y=580|Color=8388608|FontID=1|Text=R85|Name=Designator|ReadOnlyState=1
|RECORD=41|OwnerIndex=1260|IndexInSheet=-1|OwnerPartId=-1|Location.X=1070|Location.Y=580|Color=8388608|FontID=1|Text=27_1%_0402|Name=Comment
|RECORD=44|OwnerIndex=1260
|RECORD=45|OwnerIndex=1275|IndexInSheet=-1|Description=Chip Resistor, 2-Leads, Body 1.00x0.50mm, IPC Medium Density|UseComponentLibrary=T|ModelName=RESC1005X40X25NL05T05|ModelType=PCBLIB|DatafileCount=1|ModelDatafileEntity0=RESC1005X40X25NL05T05|ModelDatafileKind0=PCBLib|IsCurrent=T|DatalinksLocked=T|DatabaseDatalinksLocked=T
|RECORD=46|OwnerIndex=1276
|RECORD=48|OwnerIndex=1276
|RECORD=41|OwnerIndex=1278|IndexInSheet=-1|OwnerPartId=-1|Color=8388608|FontID=1|IsHidden=T|Text=2D|Name=Available Preview Images
|RECORD=45|OwnerIndex=1275|IndexInSheet=-1|Description=Chip Resistor, 2-Leads, Body 1.00x0.50mm, IPC High Density|UseComponentLibrary=T|ModelName=RESC1005X40X25LL05T05|ModelType=PCBLIB|DatafileCount=1|ModelDatafileEntity0=RESC1005X40X25LL05T05|ModelDatafileKind0=PCBLib|DatalinksLocked=T|DatabaseDatalinksLocked=T
|RECORD=46|OwnerIndex=1280
|RECORD=48|OwnerIndex=1280
|RECORD=41|OwnerIndex=1282|IndexInSheet=-1|OwnerPartId=-1|Color=8388608|FontID=1|IsHidden=T|Text=2D|Name=Available Preview Images
|RECORD=45|OwnerIndex=1275|IndexInSheet=-1|Description=Chip Resistor, 2-Leads, Body 1.00x0.50mm, IPC Low Density|UseComponentLibrary=T|ModelName=RESC1005X40X25ML05T05|ModelType=PCBLIB|DatafileCount=1|ModelDatafileEntity0=RESC1005X40X25ML05T05|ModelDatafileKind0=PCBLib|DatalinksLocked=T|DatabaseDatalinksLocked=T
|RECORD=46|OwnerIndex=1284
|RECORD=48|OwnerIndex=1284
|RECORD=41|OwnerIndex=1286|IndexInSheet=-1|OwnerPartId=-1|Color=8388608|FontID=1|IsHidden=T|Text=2D|Name=Available Preview Images
|RECORD=27|IndexInSheet=163|OwnerPartId=-1|LineWidth=1|Color=8388608|LocationCount=2|X1=1100|Y1=580|X2=1200|Y2=580
|RECORD=17|IndexInSheet=164|OwnerPartId=-1|ShowNetName=T|Location.X=1390|Location.Y=600|Color=255|FontID=1|Text=UART1_TXD|IsCrossSheetConnector=T
|RECORD=17|IndexInSheet=165|OwnerPartId=-1|Style=1|ShowNetName=T|Location.X=1390|Location.Y=560|Color=255|FontID=1|Text=UART1_RXD|IsCrossSheetConnector=T
|RECORD=27|IndexInSheet=166|OwnerPartId=-1|LineWidth=1|Color=8388608|LocationCount=3|X1=1340|Y1=560|X2=1370|Y2=560|X3=1390|Y3=560
|RECORD=27|IndexInSheet=167|OwnerPartId=-1|LineWidth=1|Color=8388608|LocationCount=3|X1=1390|Y1=600|X2=1360|Y2=600|X3=1340|Y3=600
|RECORD=17|IndexInSheet=168|OwnerPartId=-1|Style=4|ShowNetName=T|Location.X=990|Location.Y=600|Orientation=2|Color=128|FontID=1|Text=GND
|RECORD=17|IndexInSheet=169|OwnerPartId=-1|Style=4|ShowNetName=T|Location.X=990|Location.Y=560|Orientation=2|Color=128|FontID=1|Text=GND
|RECORD=17|IndexInSheet=170|OwnerPartId=-1|ShowNetName=T|Location.X=1020|Location.Y=540|Orientation=2|Color=255|FontID=1|Text=FTDI_TX|IsCrossSheetConnector=T
|RECORD=17|IndexInSheet=171|OwnerPartId=-1|Style=1|ShowNetName=T|Location.X=1020|Location.Y=580|Orientation=2|Color=255|FontID=1|Text=FTDI_RX|IsCrossSheetConnector=T
|RECORD=27|IndexInSheet=172|OwnerPartId=-1|LineWidth=1|Color=8388608|LocationCount=2|X1=990|Y1=600|X2=1060|Y2=600
|RECORD=27|IndexInSheet=173|OwnerPartId=-1|LineWidth=1|Color=8388608|LocationCount=2|X1=1060|Y1=560|X2=990|Y2=560
|RECORD=27|IndexInSheet=174|OwnerPartId=-1|LineWidth=1|Color=8388608|LocationCount=2|X1=1020|Y1=580|X2=1060|Y2=580
|RECORD=27|IndexInSheet=175|OwnerPartId=-1|LineWidth=1|Color=8388608|LocationCount=2|X1=1060|Y1=540|X2=1020|Y2=540
|RECORD=1|LibReference=12a319ab100cd6cfe745e35972674f5|ComponentDescription=IC SWITCH SPDT DUAL 12UQFN|PartCount=2|DisplayModeCount=1|IndexInSheet=176|OwnerPartId=-1|Location.X=480|Location.Y=230|CurrentPartId=1|LibraryPath=*|SourceLibraryName=Altium Content Vault|TargetFileName=*|AreaColor=11599871|Color=128|PartIDLocked=T|DesignItemId=CMP-04892-000114-1|AllPinCount=12
|RECORD=14|OwnerIndex=1301|IsNotAccesible=T|OwnerPartId=1|Location.X=500|Location.Y=70|Corner.X=600|Corner.Y=240|LineWidth=1|Color=128|AreaColor=11599871|IsSolid=T
|RECORD=2|OwnerIndex=1301|OwnerPartId=1|Electrical=7|PinConglomerate=58|PinLength=20|Location.X=500|Location.Y=230|Name=VCC|Designator=9|PinName_PositionConglomerate=16|Name_CustomFontID=1|PinDesignator_PositionConglomerate=16|Designator_CustomFontID=1|PinPropagationDelay=0.000000E+000
|RECORD=2|OwnerIndex=1301|OwnerPartId=1|PinConglomerate=58|PinLength=20|Location.X=500|Location.Y=130|Name=SEL1|Designator=1|PinName_PositionConglomerate=16|Name_CustomFontID=1|PinDesignator_PositionConglomerate=16|Designator_CustomFontID=1|PinPropagationDelay=0.000000E+000
|RECORD=2|OwnerIndex=1301|OwnerPartId=1|PinConglomerate=58|PinLength=20|Location.X=500|Location.Y=120|Name=SEL2|Designator=5|PinName_PositionConglomerate=16|Name_CustomFontID=1|PinDesignator_PositionConglomerate=16|Designator_CustomFontID=1|PinPropagationDelay=0.000000E+000
|RECORD=2|OwnerIndex=1301|OwnerPartId=1|Electrical=4|PinConglomerate=58|PinLength=20|Location.X=500|Location.Y=190|Name=NO1|Designator=2|PinName_PositionConglomerate=16|Name_CustomFontID=1|PinDesignator_PositionConglomerate=16|Designator_CustomFontID=1|PinPropagationDelay=0.000000E+000
|RECORD=2|OwnerIndex=1301|OwnerPartId=1|Electrical=4|PinConglomerate=58|PinLength=20|Location.X=500|Location.Y=150|Name=NO2|Designator=4|PinName_PositionConglomerate=16|Name_CustomFontID=1|PinDesignator_PositionConglomerate=16|Designator_CustomFontID=1|PinPropagationDelay=0.000000E+000
|RECORD=2|OwnerIndex=1301|OwnerPartId=1|Electrical=4|PinConglomerate=56|PinLength=20|Location.X=600|Location.Y=210|Name=COM1|Designator=11|PinName_PositionConglomerate=16|Name_CustomFontID=1|PinDesignator_PositionConglomerate=16|Designator_CustomFontID=1|PinPropagationDelay=0.000000E+000
|RECORD=2|OwnerIndex=1301|OwnerPartId=1|Electrical=4|PinConglomerate=56|PinLength=20|Location.X=600|Location.Y=170|Name=COM2|Designator=7|PinName_PositionConglomerate=16|Name_CustomFontID=1|PinDesignator_PositionConglomerate=16|Designator_CustomFontID=1|PinPropagationDelay=0.000000E+000
|RECORD=2|OwnerIndex=1301|OwnerPartId=1|Electrical=3|PinConglomerate=58|PinLength=20|Location.X=500|Location.Y=80|Name=F\L\T\|Designator=12|PinName_PositionConglomerate=16|Name_CustomFontID=1|PinDesignator_PositionConglomerate=16|Designator_CustomFontID=1|PinPropagationDelay=0.000000E+000
|RECORD=2|OwnerIndex=1301|OwnerPartId=1|PinConglomerate=58|PinLength=20|Location.X=500|Location.Y=100|Name=O\E\|Designator=6|PinName_PositionConglomerate=16|Name_CustomFontID=1|PinDesignator_PositionConglomerate=16|Designator_CustomFontID=1|PinPropagationDelay=0.000000E+000
|RECORD=2|OwnerIndex=1301|OwnerPartId=1|Electrical=4|PinConglomerate=58|PinLength=20|Location.X=500|Location.Y=210|Name=NC1|Designator=10|PinName_PositionConglomerate=16|Name_CustomFontID=1|PinDesignator_PositionConglomerate=16|Designator_CustomFontID=1|PinPropagationDelay=0.000000E+000
|RECORD=2|OwnerIndex=1301|OwnerPartId=1|Electrical=4|PinConglomerate=58|PinLength=20|Location.X=500|Location.Y=170|Name=NC2|Designator=8|PinName_PositionConglomerate=16|Name_CustomFontID=1|PinDesignator_PositionConglomerate=16|Designator_CustomFontID=1|PinPropagationDelay=0.000000E+000
|RECORD=2|OwnerIndex=1301|OwnerPartId=1|Electrical=7|PinConglomerate=56|PinLength=20|Location.X=600|Location.Y=80|Name=GND|Designator=3|PinName_PositionConglomerate=16|Name_CustomFontID=1|PinDesignator_PositionConglomerate=16|Designator_CustomFontID=1|PinPropagationDelay=0.000000E+000
|RECORD=41|OwnerIndex=1301|IndexInSheet=13|OwnerPartId=-1|Location.X=478|Location.Y=240|Color=8388608|FontID=1|IsHidden=T|Text=12|Name=Number of Pins
|RECORD=41|OwnerIndex=1301|IndexInSheet=14|OwnerPartId=-1|Location.X=478|Location.Y=240|Color=8388608|FontID=1|IsHidden=T|Text=2|Name=Number of Circuits
|RECORD=41|OwnerIndex=1301|IndexInSheet=15|OwnerPartId=-1|Location.X=478|Location.Y=240|Color=8388608|FontID=1|IsHidden=T|Text=-40°C|Name=Min Operating Temperature
|RECORD=41|OwnerIndex=1301|IndexInSheet=16|OwnerPartId=-1|Location.X=478|Location.Y=240|Color=8388608|FontID=1|IsHidden=T|Text=Yes|Name=RoHS Compliant
|RECORD=41|OwnerIndex=1301|IndexInSheet=17|OwnerPartId=-1|Location.X=478|Location.Y=240|Color=8388608|FontID=1|IsHidden=T|Text=1.2GHz|Name=-3db Bandwidth
|RECORD=41|OwnerIndex=1301|IndexInSheet=18|OwnerPartId=-1|Location.X=478|Location.Y=240|Color=8388608|FontID=1|IsHidden=T|Text=125°C|Name=Max Operating Temperature
|RECORD=41|OwnerIndex=1301|IndexInSheet=19|OwnerPartId=-1|Location.X=478|Location.Y=240|Color=8388608|FontID=1|IsHidden=T|Text=2|Name=Number of Channels
|RECORD=41|OwnerIndex=1301|IndexInSheet=20|OwnerPartId=-1|Location.X=478|Location.Y=240|Color=8388608|FontID=1|IsHidden=T|Text=18R|Name=On-State Resistance
|RECORD=41|OwnerIndex=1301|IndexInSheet=21|OwnerPartId=-1|Location.X=478|Location.Y=240|Color=8388608|FontID=1|IsHidden=T|Text=Tape and Reel|Name=Packaging
|RECORD=34|OwnerIndex=1301|IndexInSheet=-1|OwnerPartId=-1|Location.X=500|Location.Y=240|Color=8388608|FontID=1|Text=U23|Name=Designator|ReadOnlyState=1
|RECORD=41|OwnerIndex=1301|IndexInSheet=-1|OwnerPartId=1|Location.X=500|Location.Y=60|Color=8388608|FontID=1|Text=TMUX1072RUTR|Name=Comment
|RECORD=44|OwnerIndex=1301
|RECORD=45|OwnerIndex=1338|IndexInSheet=-1|UseComponentLibrary=T|ModelName=FP-RUT0012A-MFG|ModelType=PCBLIB|DatafileCount=1|ModelDatafileEntity0=FP-RUT0012A-MFG|ModelDatafileKind0=PCBLib|IsCurrent=T|DatalinksLocked=T|DatabaseDatalinksLocked=T
|RECORD=46|OwnerIndex=1339
|RECORD=48|OwnerIndex=1339
|RECORD=17|IndexInSheet=177|OwnerPartId=-1|Style=4|ShowNetName=T|Location.X=460|Location.Y=70|Orientation=3|Color=128|FontID=1|Text=GND
|RECORD=1|LibReference=b4654b650e69147ec39a6b967a45e02|ComponentDescription=General Purpose Ceramic Capacitor, 0402, 100nF, 10%, X7R, 15%, 25V|PartCount=2|DisplayModeCount=1|IndexInSheet=178|OwnerPartId=-1|Location.X=420|Location.Y=260|CurrentPartId=1|LibraryPath=*|SourceLibraryName=Altium Content Vault|TargetFileName=*|AreaColor=11599871|Color=128|PartIDLocked=T|DesignItemId=CMP-2008-02519-2|AllPinCount=2
|RECORD=2|OwnerIndex=1343|OwnerPartId=1|Electrical=4|PinConglomerate=49|PinLength=7|Location.X=420|Location.Y=253|Name=1|Designator=1|PinPropagationDelay=0.000000E+000
|RECORD=2|OwnerIndex=1343|OwnerPartId=1|Electrical=4|PinConglomerate=51|PinLength=6|Location.X=420|Location.Y=246|Name=2|Designator=2|PinPropagationDelay=0.000000E+000
|RECORD=13|OwnerIndex=1343|IsNotAccesible=T|IndexInSheet=2|OwnerPartId=1|Location.X=430|Location.Y=253|Corner.X=410|Corner.Y=253|LineWidth=1|Color=16711680
|RECORD=13|OwnerIndex=1343|IsNotAccesible=T|IndexInSheet=3|OwnerPartId=1|Location.X=430|Location.Y=247|Corner.X=410|Corner.Y=247|LineWidth=1|Color=16711680
|RECORD=13|OwnerIndex=1343|IsNotAccesible=T|IndexInSheet=4|OwnerPartId=1|Location.X=420|Location.Y=253|Corner.X=420|Corner.Y=256|LineWidth=1|Color=16711680
|RECORD=13|OwnerIndex=1343|IsNotAccesible=T|IndexInSheet=5|OwnerPartId=1|Location.X=420|Location.Y=246|Corner.X=420|Corner.Y=245|LineWidth=1|Color=16711680
|RECORD=41|OwnerIndex=1343|IndexInSheet=6|OwnerPartId=-1|Location.X=409|Location.Y=262|Color=8388608|FontID=1|IsHidden=T|Text=1|Name=Package Quantity
|RECORD=41|OwnerIndex=1343|IndexInSheet=7|OwnerPartId=-1|Location.X=409|Location.Y=262|Color=8388608|FontID=1|IsHidden=T|Text=100nF|Name=Capacitance
|RECORD=41|OwnerIndex=1343|IndexInSheet=8|OwnerPartId=-1|Location.X=409|Location.Y=262|Color=8388608|FontID=1|IsHidden=T|Text=-55°C|Name=Min Operating Temperature
|RECORD=41|OwnerIndex=1343|IndexInSheet=9|OwnerPartId=-1|Location.X=409|Location.Y=262|Color=8388608|FontID=1|IsHidden=T|Text=25V|Name=Voltage
|RECORD=41|OwnerIndex=1343|IndexInSheet=10|OwnerPartId=-1|Location.X=409|Location.Y=262|Color=8388608|FontID=1|IsHidden=T|Text=25V|Name=Voltage Rating
|RECORD=41|OwnerIndex=1343|IndexInSheet=11|OwnerPartId=-1|Location.X=409|Location.Y=262|Color=8388608|FontID=1|IsHidden=T|Text=Flat|Name=Construction
|RECORD=41|OwnerIndex=1343|IndexInSheet=12|OwnerPartId=-1|Location.X=409|Location.Y=262|Color=8388608|FontID=1|IsHidden=T|Text=125°C|Name=Max Operating Temperature
|RECORD=41|OwnerIndex=1343|IndexInSheet=13|OwnerPartId=-1|Location.X=409|Location.Y=262|Color=8388608|FontID=1|IsHidden=T|Text=No|Name=Radiation Hardening
|RECORD=41|OwnerIndex=1343|IndexInSheet=14|OwnerPartId=-1|Location.X=409|Location.Y=262|Color=8388608|FontID=1|IsHidden=T|Text=0.5mm|Name=Depth
|RECORD=41|OwnerIndex=1343|IndexInSheet=15|OwnerPartId=-1|Location.X=409|Location.Y=262|Color=8388608|FontID=1|IsHidden=T|Text=0.022inch|Name=Thickness
|RECORD=41|OwnerIndex=1343|IndexInSheet=16|OwnerPartId=-1|Location.X=409|Location.Y=262|Color=8388608|FontID=1|IsHidden=T|Text=25V|Name=Voltage Rating (DC)
|RECORD=41|OwnerIndex=1343|IndexInSheet=17|OwnerPartId=-1|Location.X=409|Location.Y=262|Color=8388608|FontID=1|IsHidden=T|Text=2|Name=Number of Pins
|RECORD=41|OwnerIndex=1343|IndexInSheet=18|OwnerPartId=-1|Location.X=409|Location.Y=262|Color=8388608|FontID=1|IsHidden=T|Text=Lead Free|Name=Lead Free
|RECORD=41|OwnerIndex=1343|IndexInSheet=19|OwnerPartId=-1|Location.X=409|Location.Y=262|Color=8388608|FontID=1|IsHidden=T|Text=-|Name=Series
|RECORD=41|OwnerIndex=1343|IndexInSheet=20|OwnerPartId=-1|Location.X=409|Location.Y=262|Color=8388608|FontID=1|IsHidden=T|Text=No SVHC|Name=REACH SVHC
|RECORD=41|OwnerIndex=1343|IndexInSheet=21|OwnerPartId=-1|Location.X=409|Location.Y=262|Color=8388608|FontID=1|IsHidden=T|Text=1mm|Name=Length
|RECORD=41|OwnerIndex=1343|IndexInSheet=22|OwnerPartId=-1|Location.X=409|Location.Y=262|Color=8388608|FontID=1|IsHidden=T|Text=X7R|Name=Dielectric
|RECORD=41|OwnerIndex=1343|IndexInSheet=23|OwnerPartId=-1|Location.X=409|Location.Y=262|Color=8388608|FontID=1|IsHidden=T|Text=Yes|Name=RoHS Compliant
|RECORD=41|OwnerIndex=1343|IndexInSheet=24|OwnerPartId=-1|Location.X=409|Location.Y=262|Color=8388608|FontID=1|IsHidden=T|Text=Surface Mount|Name=Mount
|RECORD=41|OwnerIndex=1343|IndexInSheet=25|OwnerPartId=-1|Location.X=409|Location.Y=262|Color=8388608|FontID=1|IsHidden=T|Text=Tape and Reel|Name=Packaging
|RECORD=41|OwnerIndex=1343|IndexInSheet=26|OwnerPartId=-1|Location.X=409|Location.Y=262|Color=8388608|FontID=1|IsHidden=T|Text=0402|Name=Case/Package
|RECORD=41|OwnerIndex=1343|IndexInSheet=27|OwnerPartId=-1|Location.X=409|Location.Y=262|Color=8388608|FontID=1|IsHidden=T|Text=0402|Name=Case Code (Imperial)
|RECORD=41|OwnerIndex=1343|IndexInSheet=28|OwnerPartId=-1|Location.X=409|Location.Y=262|Color=8388608|FontID=1|IsHidden=T|Text=SMD/SMT|Name=Termination
|RECORD=41|OwnerIndex=1343|IndexInSheet=29|OwnerPartId=-1|Location.X=409|Location.Y=262|Color=8388608|FontID=1|IsHidden=T|Text=0.02inch|Name=Width
|RECORD=41|OwnerIndex=1343|IndexInSheet=30|OwnerPartId=-1|Location.X=409|Location.Y=262|Color=8388608|FontID=1|IsHidden=T|Text=1005|Name=Case Code (Metric)
|RECORD=41|OwnerIndex=1343|IndexInSheet=31|OwnerPartId=-1|Location.X=409|Location.Y=262|Color=8388608|FontID=1|IsHidden=T|Text=10%|Name=Tolerance
|RECORD=34|OwnerIndex=1343|IndexInSheet=-1|OwnerPartId=-1|Location.X=410|Location.Y=240|Orientation=1|Color=8388608|FontID=2|Text=C96|Name=Designator|ReadOnlyState=1
|RECORD=41|OwnerIndex=1343|IndexInSheet=-1|OwnerPartId=1|Location.X=440|Location.Y=225|Orientation=1|Color=8388608|FontID=2|Text=0.1uF_25V_0402|Name=Comment
|RECORD=44|OwnerIndex=1343
|RECORD=45|OwnerIndex=1380|IndexInSheet=-1|UseComponentLibrary=T|ModelName=FP-0402-L_1_0_1-W_0_5_0_1-IPC_C|ModelType=PCBLIB|DatafileCount=1|ModelDatafileEntity0=FP-0402-L_1_0_1-W_0_5_0_1-IPC_C|ModelDatafileKind0=PCBLib|IsCurrent=T|DatalinksLocked=T|DatabaseDatalinksLocked=T
|RECORD=46|OwnerIndex=1381
|RECORD=48|OwnerIndex=1381
|RECORD=45|OwnerIndex=1380|IndexInSheet=-1|UseComponentLibrary=T|ModelName=FP-0402-L_1_0_1-W_0_5_0_1-IPC_B|ModelType=PCBLIB|DatafileCount=1|ModelDatafileEntity0=FP-0402-L_1_0_1-W_0_5_0_1-IPC_B|ModelDatafileKind0=PCBLib|DatalinksLocked=T|DatabaseDatalinksLocked=T
|RECORD=46|OwnerIndex=1384
|RECORD=48|OwnerIndex=1384
|RECORD=45|OwnerIndex=1380|IndexInSheet=-1|UseComponentLibrary=T|ModelName=FP-0402-L_1_0_1-W_0_5_0_1-MFG|ModelType=PCBLIB|DatafileCount=1|ModelDatafileEntity0=FP-0402-L_1_0_1-W_0_5_0_1-MFG|ModelDatafileKind0=PCBLib|DatalinksLocked=T|DatabaseDatalinksLocked=T
|RECORD=46|OwnerIndex=1387
|RECORD=48|OwnerIndex=1387
|RECORD=45|OwnerIndex=1380|IndexInSheet=-1|UseComponentLibrary=T|ModelName=FP-0402-L_1_0_1-W_0_5_0_1-IPC_A|ModelType=PCBLIB|DatafileCount=1|ModelDatafileEntity0=FP-0402-L_1_0_1-W_0_5_0_1-IPC_A|ModelDatafileKind0=PCBLib|DatalinksLocked=T|DatabaseDatalinksLocked=T
|RECORD=46|OwnerIndex=1390
|RECORD=48|OwnerIndex=1390
|RECORD=17|IndexInSheet=179|OwnerPartId=-1|ShowNetName=T|Location.X=420|Location.Y=310|Orientation=1|Color=128|FontID=1|Text=+3.3V
|RECORD=17|IndexInSheet=180|OwnerPartId=-1|Style=4|ShowNetName=T|Location.X=420|Location.Y=230|Orientation=3|Color=128|FontID=1|Text=GND
|RECORD=4|IndexInSheet=181|OwnerPartId=-1|Location.X=480|Location.Y=350|Color=8388608|FontID=1|Text=Atomic clock PPS input / output select
|RECORD=17|IndexInSheet=182|OwnerPartId=-1|ShowNetName=T|Location.X=370|Location.Y=130|Orientation=2|Color=255|FontID=1|Text=DIP_SW_PPS_SEL|IsCrossSheetConnector=T
|RECORD=17|IndexInSheet=183|OwnerPartId=-1|Style=4|ShowNetName=T|Location.X=630|Location.Y=70|Orientation=3|Color=128|FontID=1|Text=GND
|RECORD=27|IndexInSheet=184|OwnerPartId=-1|LineWidth=1|Color=8388608|LocationCount=2|X1=480|Y1=80|X2=460|Y2=80
|RECORD=27|IndexInSheet=185|OwnerPartId=-1|LineWidth=1|Color=8388608|LocationCount=4|X1=420|Y1=290|X2=450|Y2=290|X3=450|Y3=230|X4=480|Y4=230
|RECORD=27|IndexInSheet=186|OwnerPartId=-1|LineWidth=1|Color=8388608|LocationCount=2|X1=420|Y1=230|X2=420|Y2=240
|RECORD=27|IndexInSheet=187|OwnerPartId=-1|LineWidth=1|Color=8388608|LocationCount=3|X1=480|Y1=120|X2=460|Y2=120|X3=460|Y3=130
|RECORD=27|IndexInSheet=188|OwnerPartId=-1|LineWidth=1|Color=8388608|LocationCount=3|X1=620|Y1=80|X2=630|Y2=80|X3=630|Y3=70
|RECORD=17|IndexInSheet=189|OwnerPartId=-1|ShowNetName=T|Location.X=290|Location.Y=210|Orientation=2|Color=255|FontID=1|Text=MAC_PPS_OUT|IsCrossSheetConnector=T
|RECORD=27|IndexInSheet=190|OwnerPartId=-1|LineWidth=1|Color=8388608|LocationCount=3|X1=370|Y1=130|X2=460|Y2=130|X3=480|Y3=130
|RECORD=27|IndexInSheet=191|OwnerPartId=-1|LineWidth=1|Color=8388608|LocationCount=4|X1=480|Y1=100|X2=460|Y2=100|X3=460|Y3=80|X4=460|Y4=70
|RECORD=27|IndexInSheet=192|OwnerPartId=-1|LineWidth=1|Color=8388608|LocationCount=3|X1=420|Y1=260|X2=420|Y2=290|X3=420|Y3=310
|RECORD=4|IndexInSheet=193|OwnerPartId=-1|Location.X=40|Location.Y=210|Color=8388608|FontID=1|Text=Single ended PPS output
|RECORD=1|LibReference=RES|PartCount=2|DisplayModeCount=2|IndexInSheet=194|OwnerPartId=-1|Location.X=330|Location.Y=220|CurrentPartId=1|SourceLibraryName=Altium Content Vault|TargetFileName=*|AreaColor=11599871|Color=128|PartIDLocked=F|DesignItemId=CMP-2002-07709-1|AllPinCount=2
|RECORD=2|OwnerIndex=1408|OwnerPartId=1|OwnerPartDisplayMode=1|FormalType=1|Electrical=4|PinConglomerate=32|PinLength=10|Location.X=350|Location.Y=210|Name=2|Designator=2|PinPropagationDelay=0.000000E+000
|RECORD=2|OwnerIndex=1408|OwnerPartId=1|OwnerPartDisplayMode=1|FormalType=1|Electrical=4|PinConglomerate=34|PinLength=10|Location.X=330|Location.Y=210|Name=1|Designator=1|PinPropagationDelay=0.000000E+000
|RECORD=14|OwnerIndex=1408|IsNotAccesible=T|IndexInSheet=2|OwnerPartId=1|OwnerPartDisplayMode=1|Location.X=330|Location.Y=206|Corner.X=350|Corner.Y=214|LineWidth=1|Color=16711680|AreaColor=11599871
|RECORD=2|OwnerIndex=1408|OwnerPartId=1|FormalType=1|Electrical=4|PinConglomerate=32|PinLength=10|Location.X=350|Location.Y=210|Name=2|Designator=2|PinPropagationDelay=0.000000E+000
|RECORD=2|OwnerIndex=1408|OwnerPartId=1|FormalType=1|Electrical=4|PinConglomerate=34|PinLength=10|Location.X=330|Location.Y=210|Name=1|Designator=1|PinPropagationDelay=0.000000E+000
|RECORD=6|OwnerIndex=1408|IsNotAccesible=T|IndexInSheet=5|OwnerPartId=1|LineWidth=1|Color=16711680|LocationCount=10|X1=350|Y1=210|X2=346|Y2=210|X3=345|Y3=208|X4=343|Y4=212|X5=341|Y5=208|X6=339|Y6=212|X7=337|Y7=208|X8=335|Y8=212|X9=334|Y9=210|X10=330|Y10=210
|RECORD=41|OwnerIndex=1408|IndexInSheet=6|OwnerPartId=-1|Location.X=318|Location.Y=223|Color=8388608|FontID=1|IsHidden=T|Text=Yageo / Phycomp|Name=Manufacturer
|RECORD=41|OwnerIndex=1408|IndexInSheet=7|OwnerPartId=-1|Location.X=318|Location.Y=223|Color=8388608|FontID=1|IsHidden=T|Text=RC0402FR-0749R9L|Name=Part Number
|RECORD=34|OwnerIndex=1408|IndexInSheet=-1|OwnerPartId=-1|Location.X=310|Location.Y=210|Color=8388608|FontID=1|Text=R96|Name=Designator|ReadOnlyState=1
|RECORD=41|OwnerIndex=1408|IndexInSheet=-1|OwnerPartId=-1|Location.X=350|Location.Y=210|Color=8388608|FontID=1|Text=49.9_1%_0402|Name=Comment
|RECORD=44|OwnerIndex=1408
|RECORD=45|OwnerIndex=1423|IndexInSheet=-1|Description=Chip Resistor, 2-Leads, Body 1.00x0.50mm, IPC High Density|UseComponentLibrary=T|ModelName=RESC1005X40X25LL05T10|ModelType=PCBLIB|DatafileCount=1|ModelDatafileEntity0=RESC1005X40X25LL05T10|ModelDatafileKind0=PCBLib|IsCurrent=T|DatalinksLocked=T|DatabaseDatalinksLocked=T
|RECORD=46|OwnerIndex=1424
|RECORD=48|OwnerIndex=1424
|RECORD=41|OwnerIndex=1426|IndexInSheet=-1|OwnerPartId=-1|Color=8388608|FontID=1|IsHidden=T|Text=2D|Name=Available Preview Images
|RECORD=45|OwnerIndex=1423|IndexInSheet=-1|Description=Chip Resistor, 2-Leads, Body 1.00x0.50mm, IPC Low Density|UseComponentLibrary=T|ModelName=RESC1005X40X25ML05T10|ModelType=PCBLIB|DatafileCount=1|ModelDatafileEntity0=RESC1005X40X25ML05T10|ModelDatafileKind0=PCBLib|DatalinksLocked=T|DatabaseDatalinksLocked=T
|RECORD=46|OwnerIndex=1428
|RECORD=48|OwnerIndex=1428
|RECORD=41|OwnerIndex=1430|IndexInSheet=-1|OwnerPartId=-1|Color=8388608|FontID=1|IsHidden=T|Text=2D|Name=Available Preview Images
|RECORD=45|OwnerIndex=1423|IndexInSheet=-1|Description=Chip Resistor, 2-Leads, Body 1.00x0.50mm, IPC Medium Density|UseComponentLibrary=T|ModelName=RESC1005X40X25NL05T10|ModelType=PCBLIB|DatafileCount=1|ModelDatafileEntity0=RESC1005X40X25NL05T10|ModelDatafileKind0=PCBLib|DatalinksLocked=T|DatabaseDatalinksLocked=T
|RECORD=46|OwnerIndex=1432
|RECORD=48|OwnerIndex=1432
|RECORD=41|OwnerIndex=1434|IndexInSheet=-1|OwnerPartId=-1|Color=8388608|FontID=1|IsHidden=T|Text=2D|Name=Available Preview Images
|RECORD=27|IndexInSheet=195|OwnerPartId=-1|LineWidth=1|Color=8388608|LocationCount=2|X1=360|Y1=210|X2=480|Y2=210
|RECORD=27|IndexInSheet=196|OwnerPartId=-1|LineWidth=1|Color=8388608|LocationCount=2|X1=320|Y1=210|X2=290|Y2=210
|RECORD=17|IndexInSheet=197|OwnerPartId=-1|Style=1|ShowNetName=T|Location.X=690|Location.Y=210|Color=255|FontID=1|Text=FPGA_MAC_PPS_OUT-|IsCrossSheetConnector=T
|RECORD=4|IndexInSheet=198|OwnerPartId=-1|Location.X=830|Location.Y=210|Color=8388608|FontID=1|Text=FPGA Single ended PPS Input
|RECORD=27|IndexInSheet=199|OwnerPartId=-1|LineWidth=1|Color=8388608|LocationCount=3|X1=620|Y1=210|X2=630|Y2=210|X3=690|Y3=210
|RECORD=17|IndexInSheet=200|OwnerPartId=-1|ShowNetName=T|Location.X=290|Location.Y=190|Orientation=2|Color=255|FontID=1|Text=FPGA_MAC_PPSDIFF_OUT|IsCrossSheetConnector=T
|RECORD=1|LibReference=RES|PartCount=2|DisplayModeCount=2|IndexInSheet=201|OwnerPartId=-1|Location.X=330|Location.Y=200|CurrentPartId=1|SourceLibraryName=Altium Content Vault|TargetFileName=*|AreaColor=11599871|Color=128|PartIDLocked=F|DesignItemId=CMP-2002-07709-1|AllPinCount=2
|RECORD=2|OwnerIndex=1442|OwnerPartId=1|OwnerPartDisplayMode=1|FormalType=1|Electrical=4|PinConglomerate=32|PinLength=10|Location.X=350|Location.Y=190|Name=2|Designator=2|PinPropagationDelay=0.000000E+000
|RECORD=2|OwnerIndex=1442|OwnerPartId=1|OwnerPartDisplayMode=1|FormalType=1|Electrical=4|PinConglomerate=34|PinLength=10|Location.X=330|Location.Y=190|Name=1|Designator=1|PinPropagationDelay=0.000000E+000
|RECORD=14|OwnerIndex=1442|IsNotAccesible=T|IndexInSheet=2|OwnerPartId=1|OwnerPartDisplayMode=1|Location.X=330|Location.Y=186|Corner.X=350|Corner.Y=194|LineWidth=1|Color=16711680|AreaColor=11599871
|RECORD=2|OwnerIndex=1442|OwnerPartId=1|FormalType=1|Electrical=4|PinConglomerate=32|PinLength=10|Location.X=350|Location.Y=190|Name=2|Designator=2|PinPropagationDelay=0.000000E+000
|RECORD=2|OwnerIndex=1442|OwnerPartId=1|FormalType=1|Electrical=4|PinConglomerate=34|PinLength=10|Location.X=330|Location.Y=190|Name=1|Designator=1|PinPropagationDelay=0.000000E+000
|RECORD=6|OwnerIndex=1442|IsNotAccesible=T|IndexInSheet=5|OwnerPartId=1|LineWidth=1|Color=16711680|LocationCount=10|X1=350|Y1=190|X2=346|Y2=190|X3=345|Y3=188|X4=343|Y4=192|X5=341|Y5=188|X6=339|Y6=192|X7=337|Y7=188|X8=335|Y8=192|X9=334|Y9=190|X10=330|Y10=190
|RECORD=41|OwnerIndex=1442|IndexInSheet=6|OwnerPartId=-1|Location.X=318|Location.Y=203|Color=8388608|FontID=1|IsHidden=T|Text=Yageo / Phycomp|Name=Manufacturer
|RECORD=41|OwnerIndex=1442|IndexInSheet=7|OwnerPartId=-1|Location.X=318|Location.Y=203|Color=8388608|FontID=1|IsHidden=T|Text=RC0402FR-0749R9L|Name=Part Number
|RECORD=34|OwnerIndex=1442|IndexInSheet=-1|OwnerPartId=-1|Location.X=310|Location.Y=190|Color=8388608|FontID=1|Text=R97|Name=Designator|ReadOnlyState=1
|RECORD=41|OwnerIndex=1442|IndexInSheet=-1|OwnerPartId=-1|Location.X=350|Location.Y=190|Color=8388608|FontID=1|Text=49.9_1%_0402|Name=Comment
|RECORD=44|OwnerIndex=1442
|RECORD=45|OwnerIndex=1457|IndexInSheet=-1|Description=Chip Resistor, 2-Leads, Body 1.00x0.50mm, IPC High Density|UseComponentLibrary=T|ModelName=RESC1005X40X25LL05T10|ModelType=PCBLIB|DatafileCount=1|ModelDatafileEntity0=RESC1005X40X25LL05T10|ModelDatafileKind0=PCBLib|IsCurrent=T|DatalinksLocked=T|DatabaseDatalinksLocked=T
|RECORD=46|OwnerIndex=1458
|RECORD=48|OwnerIndex=1458
|RECORD=41|OwnerIndex=1460|IndexInSheet=-1|OwnerPartId=-1|Color=8388608|FontID=1|IsHidden=T|Text=2D|Name=Available Preview Images
|RECORD=45|OwnerIndex=1457|IndexInSheet=-1|Description=Chip Resistor, 2-Leads, Body 1.00x0.50mm, IPC Low Density|UseComponentLibrary=T|ModelName=RESC1005X40X25ML05T10|ModelType=PCBLIB|DatafileCount=1|ModelDatafileEntity0=RESC1005X40X25ML05T10|ModelDatafileKind0=PCBLib|DatalinksLocked=T|DatabaseDatalinksLocked=T
|RECORD=46|OwnerIndex=1462
|RECORD=48|OwnerIndex=1462
|RECORD=41|OwnerIndex=1464|IndexInSheet=-1|OwnerPartId=-1|Color=8388608|FontID=1|IsHidden=T|Text=2D|Name=Available Preview Images
|RECORD=45|OwnerIndex=1457|IndexInSheet=-1|Description=Chip Resistor, 2-Leads, Body 1.00x0.50mm, IPC Medium Density|UseComponentLibrary=T|ModelName=RESC1005X40X25NL05T10|ModelType=PCBLIB|DatafileCount=1|ModelDatafileEntity0=RESC1005X40X25NL05T10|ModelDatafileKind0=PCBLib|DatalinksLocked=T|DatabaseDatalinksLocked=T
|RECORD=46|OwnerIndex=1466
|RECORD=48|OwnerIndex=1466
|RECORD=41|OwnerIndex=1468|IndexInSheet=-1|OwnerPartId=-1|Color=8388608|FontID=1|IsHidden=T|Text=2D|Name=Available Preview Images
|RECORD=27|IndexInSheet=202|OwnerPartId=-1|LineWidth=1|Color=8388608|LocationCount=2|X1=360|Y1=190|X2=480|Y2=190
|RECORD=27|IndexInSheet=203|OwnerPartId=-1|LineWidth=1|Color=8388608|LocationCount=2|X1=320|Y1=190|X2=290|Y2=190
|RECORD=4|IndexInSheet=204|OwnerPartId=-1|Location.X=40|Location.Y=190|Color=8388608|FontID=1|Text=Diff PPS Output
|RECORD=17|IndexInSheet=205|OwnerPartId=-1|Style=1|ShowNetName=T|Location.X=290|Location.Y=170|Orientation=2|Color=255|FontID=1|Text=MAC_PPS_IN|IsCrossSheetConnector=T
|RECORD=1|LibReference=RES|PartCount=2|DisplayModeCount=2|IndexInSheet=206|OwnerPartId=-1|Location.X=330|Location.Y=180|CurrentPartId=1|SourceLibraryName=Altium Content Vault|TargetFileName=*|AreaColor=11599871|Color=128|PartIDLocked=F|DesignItemId=CMP-2002-07709-1|AllPinCount=2
|RECORD=2|OwnerIndex=1474|OwnerPartId=1|OwnerPartDisplayMode=1|FormalType=1|Electrical=4|PinConglomerate=32|PinLength=10|Location.X=350|Location.Y=170|Name=2|Designator=2|PinPropagationDelay=0.000000E+000
|RECORD=2|OwnerIndex=1474|OwnerPartId=1|OwnerPartDisplayMode=1|FormalType=1|Electrical=4|PinConglomerate=34|PinLength=10|Location.X=330|Location.Y=170|Name=1|Designator=1|PinPropagationDelay=0.000000E+000
|RECORD=14|OwnerIndex=1474|IsNotAccesible=T|IndexInSheet=2|OwnerPartId=1|OwnerPartDisplayMode=1|Location.X=330|Location.Y=166|Corner.X=350|Corner.Y=174|LineWidth=1|Color=16711680|AreaColor=11599871
|RECORD=2|OwnerIndex=1474|OwnerPartId=1|FormalType=1|Electrical=4|PinConglomerate=32|PinLength=10|Location.X=350|Location.Y=170|Name=2|Designator=2|PinPropagationDelay=0.000000E+000
|RECORD=2|OwnerIndex=1474|OwnerPartId=1|FormalType=1|Electrical=4|PinConglomerate=34|PinLength=10|Location.X=330|Location.Y=170|Name=1|Designator=1|PinPropagationDelay=0.000000E+000
|RECORD=6|OwnerIndex=1474|IsNotAccesible=T|IndexInSheet=5|OwnerPartId=1|LineWidth=1|Color=16711680|LocationCount=10|X1=350|Y1=170|X2=346|Y2=170|X3=345|Y3=168|X4=343|Y4=172|X5=341|Y5=168|X6=339|Y6=172|X7=337|Y7=168|X8=335|Y8=172|X9=334|Y9=170|X10=330|Y10=170
|RECORD=41|OwnerIndex=1474|IndexInSheet=6|OwnerPartId=-1|Location.X=318|Location.Y=183|Color=8388608|FontID=1|IsHidden=T|Text=Yageo / Phycomp|Name=Manufacturer
|RECORD=41|OwnerIndex=1474|IndexInSheet=7|OwnerPartId=-1|Location.X=318|Location.Y=183|Color=8388608|FontID=1|IsHidden=T|Text=RC0402FR-0749R9L|Name=Part Number
|RECORD=34|OwnerIndex=1474|IndexInSheet=-1|OwnerPartId=-1|Location.X=310|Location.Y=170|Color=8388608|FontID=1|Text=R98|Name=Designator|ReadOnlyState=1
|RECORD=41|OwnerIndex=1474|IndexInSheet=-1|OwnerPartId=-1|Location.X=350|Location.Y=170|Color=8388608|FontID=1|Text=49.9_1%_0402|Name=Comment
|RECORD=44|OwnerIndex=1474
|RECORD=45|OwnerIndex=1489|IndexInSheet=-1|Description=Chip Resistor, 2-Leads, Body 1.00x0.50mm, IPC High Density|UseComponentLibrary=T|ModelName=RESC1005X40X25LL05T10|ModelType=PCBLIB|DatafileCount=1|ModelDatafileEntity0=RESC1005X40X25LL05T10|ModelDatafileKind0=PCBLib|IsCurrent=T|DatalinksLocked=T|DatabaseDatalinksLocked=T
|RECORD=46|OwnerIndex=1490
|RECORD=48|OwnerIndex=1490
|RECORD=41|OwnerIndex=1492|IndexInSheet=-1|OwnerPartId=-1|Color=8388608|FontID=1|IsHidden=T|Text=2D|Name=Available Preview Images
|RECORD=45|OwnerIndex=1489|IndexInSheet=-1|Description=Chip Resistor, 2-Leads, Body 1.00x0.50mm, IPC Low Density|UseComponentLibrary=T|ModelName=RESC1005X40X25ML05T10|ModelType=PCBLIB|DatafileCount=1|ModelDatafileEntity0=RESC1005X40X25ML05T10|ModelDatafileKind0=PCBLib|DatalinksLocked=T|DatabaseDatalinksLocked=T
|RECORD=46|OwnerIndex=1494
|RECORD=48|OwnerIndex=1494
|RECORD=41|OwnerIndex=1496|IndexInSheet=-1|OwnerPartId=-1|Color=8388608|FontID=1|IsHidden=T|Text=2D|Name=Available Preview Images
|RECORD=45|OwnerIndex=1489|IndexInSheet=-1|Description=Chip Resistor, 2-Leads, Body 1.00x0.50mm, IPC Medium Density|UseComponentLibrary=T|ModelName=RESC1005X40X25NL05T10|ModelType=PCBLIB|DatafileCount=1|ModelDatafileEntity0=RESC1005X40X25NL05T10|ModelDatafileKind0=PCBLib|DatalinksLocked=T|DatabaseDatalinksLocked=T
|RECORD=46|OwnerIndex=1498
|RECORD=48|OwnerIndex=1498
|RECORD=41|OwnerIndex=1500|IndexInSheet=-1|OwnerPartId=-1|Color=8388608|FontID=1|IsHidden=T|Text=2D|Name=Available Preview Images
|RECORD=1|LibReference=RES|PartCount=2|DisplayModeCount=2|IndexInSheet=207|OwnerPartId=-1|Location.X=330|Location.Y=160|CurrentPartId=1|SourceLibraryName=Altium Content Vault|TargetFileName=*|AreaColor=11599871|Color=128|PartIDLocked=F|DesignItemId=CMP-2002-07709-1|AllPinCount=2
|RECORD=2|OwnerIndex=1502|OwnerPartId=1|OwnerPartDisplayMode=1|FormalType=1|Electrical=4|PinConglomerate=32|PinLength=10|Location.X=350|Location.Y=150|Name=2|Designator=2|PinPropagationDelay=0.000000E+000
|RECORD=2|OwnerIndex=1502|OwnerPartId=1|OwnerPartDisplayMode=1|FormalType=1|Electrical=4|PinConglomerate=34|PinLength=10|Location.X=330|Location.Y=150|Name=1|Designator=1|PinPropagationDelay=0.000000E+000
|RECORD=14|OwnerIndex=1502|IsNotAccesible=T|IndexInSheet=2|OwnerPartId=1|OwnerPartDisplayMode=1|Location.X=330|Location.Y=146|Corner.X=350|Corner.Y=154|LineWidth=1|Color=16711680|AreaColor=11599871
|RECORD=2|OwnerIndex=1502|OwnerPartId=1|FormalType=1|Electrical=4|PinConglomerate=32|PinLength=10|Location.X=350|Location.Y=150|Name=2|Designator=2|PinPropagationDelay=0.000000E+000
|RECORD=2|OwnerIndex=1502|OwnerPartId=1|FormalType=1|Electrical=4|PinConglomerate=34|PinLength=10|Location.X=330|Location.Y=150|Name=1|Designator=1|PinPropagationDelay=0.000000E+000
|RECORD=6|OwnerIndex=1502|IsNotAccesible=T|IndexInSheet=5|OwnerPartId=1|LineWidth=1|Color=16711680|LocationCount=10|X1=350|Y1=150|X2=346|Y2=150|X3=345|Y3=148|X4=343|Y4=152|X5=341|Y5=148|X6=339|Y6=152|X7=337|Y7=148|X8=335|Y8=152|X9=334|Y9=150|X10=330|Y10=150
|RECORD=41|OwnerIndex=1502|IndexInSheet=6|OwnerPartId=-1|Location.X=318|Location.Y=163|Color=8388608|FontID=1|IsHidden=T|Text=Yageo / Phycomp|Name=Manufacturer
|RECORD=41|OwnerIndex=1502|IndexInSheet=7|OwnerPartId=-1|Location.X=318|Location.Y=163|Color=8388608|FontID=1|IsHidden=T|Text=RC0402FR-0749R9L|Name=Part Number
|RECORD=34|OwnerIndex=1502|IndexInSheet=-1|OwnerPartId=-1|Location.X=310|Location.Y=150|Color=8388608|FontID=1|Text=R99|Name=Designator|ReadOnlyState=1
|RECORD=41|OwnerIndex=1502|IndexInSheet=-1|OwnerPartId=-1|Location.X=350|Location.Y=150|Color=8388608|FontID=1|Text=49.9_1%_0402|Name=Comment
|RECORD=44|OwnerIndex=1502
|RECORD=45|OwnerIndex=1517|IndexInSheet=-1|Description=Chip Resistor, 2-Leads, Body 1.00x0.50mm, IPC High Density|UseComponentLibrary=T|ModelName=RESC1005X40X25LL05T10|ModelType=PCBLIB|DatafileCount=1|ModelDatafileEntity0=RESC1005X40X25LL05T10|ModelDatafileKind0=PCBLib|IsCurrent=T|DatalinksLocked=T|DatabaseDatalinksLocked=T
|RECORD=46|OwnerIndex=1518
|RECORD=48|OwnerIndex=1518
|RECORD=41|OwnerIndex=1520|IndexInSheet=-1|OwnerPartId=-1|Color=8388608|FontID=1|IsHidden=T|Text=2D|Name=Available Preview Images
|RECORD=45|OwnerIndex=1517|IndexInSheet=-1|Description=Chip Resistor, 2-Leads, Body 1.00x0.50mm, IPC Low Density|UseComponentLibrary=T|ModelName=RESC1005X40X25ML05T10|ModelType=PCBLIB|DatafileCount=1|ModelDatafileEntity0=RESC1005X40X25ML05T10|ModelDatafileKind0=PCBLib|DatalinksLocked=T|DatabaseDatalinksLocked=T
|RECORD=46|OwnerIndex=1522
|RECORD=48|OwnerIndex=1522
|RECORD=41|OwnerIndex=1524|IndexInSheet=-1|OwnerPartId=-1|Color=8388608|FontID=1|IsHidden=T|Text=2D|Name=Available Preview Images
|RECORD=45|OwnerIndex=1517|IndexInSheet=-1|Description=Chip Resistor, 2-Leads, Body 1.00x0.50mm, IPC Medium Density|UseComponentLibrary=T|ModelName=RESC1005X40X25NL05T10|ModelType=PCBLIB|DatafileCount=1|ModelDatafileEntity0=RESC1005X40X25NL05T10|ModelDatafileKind0=PCBLib|DatalinksLocked=T|DatabaseDatalinksLocked=T
|RECORD=46|OwnerIndex=1526
|RECORD=48|OwnerIndex=1526
|RECORD=41|OwnerIndex=1528|IndexInSheet=-1|OwnerPartId=-1|Color=8388608|FontID=1|IsHidden=T|Text=2D|Name=Available Preview Images
|RECORD=27|IndexInSheet=208|OwnerPartId=-1|LineWidth=1|Color=8388608|LocationCount=2|X1=360|Y1=150|X2=480|Y2=150
|RECORD=27|IndexInSheet=209|OwnerPartId=-1|LineWidth=1|Color=8388608|LocationCount=2|X1=480|Y1=170|X2=360|Y2=170
|RECORD=27|IndexInSheet=210|OwnerPartId=-1|LineWidth=1|Color=8388608|LocationCount=2|X1=290|Y1=170|X2=320|Y2=170
|RECORD=4|IndexInSheet=211|OwnerPartId=-1|Location.X=40|Location.Y=170|Color=8388608|FontID=1|Text=Single ended PPS input
|RECORD=17|IndexInSheet=212|OwnerPartId=-1|Style=1|ShowNetName=T|Location.X=290|Location.Y=150|Orientation=2|Color=255|FontID=1|Text=FPGA_MAC_PPS_DIFF_IN0|IsCrossSheetConnector=T
|RECORD=27|IndexInSheet=213|OwnerPartId=-1|LineWidth=1|Color=8388608|LocationCount=2|X1=290|Y1=150|X2=320|Y2=150
|RECORD=4|IndexInSheet=214|OwnerPartId=-1|Location.X=40|Location.Y=150|Color=8388608|FontID=1|Text=Single ended to diff PPS input
|RECORD=17|IndexInSheet=215|OwnerPartId=-1|ShowNetName=T|Location.X=690|Location.Y=170|Color=255|FontID=1|Text=FPGA_MAC_PPS_IN0-|IsCrossSheetConnector=T
|RECORD=27|IndexInSheet=216|OwnerPartId=-1|LineWidth=1|Color=8388608|LocationCount=3|X1=620|Y1=170|X2=660|Y2=170|X3=690|Y3=170
|RECORD=4|IndexInSheet=217|OwnerPartId=-1|Location.X=830|Location.Y=160|Color=8388608|FontID=1|Text=FPGA Single ended PPS Output
|RECORD=17|IndexInSheet=218|OwnerPartId=-1|ShowNetName=T|Location.X=1090|Location.Y=350|Orientation=1|Color=128|FontID=1|Text=+3.3V
|RECORD=27|IndexInSheet=219|OwnerPartId=-1|LineWidth=1|Color=8388608|LocationCount=2|X1=1090|Y1=280|X2=1090|Y2=260
|RECORD=27|IndexInSheet=220|OwnerPartId=-1|LineWidth=1|Color=8388608|LocationCount=2|X1=1090|Y1=340|X2=1090|Y2=350
|RECORD=1|LibReference=8706943c75ba83719d021d2fdc84c58|ComponentDescription=LED RED DIFFUSED SMD|PartCount=2|DisplayModeCount=1|IndexInSheet=221|OwnerPartId=-1|Location.X=1090|Location.Y=340|Orientation=3|CurrentPartId=1|LibraryPath=*|SourceLibraryName=Altium Content Vault|TargetFileName=*|AreaColor=11599871|Color=128|PartIDLocked=T|DesignItemId=CMP-57192-000012-1|AllPinCount=2
|RECORD=2|OwnerIndex=1543|OwnerPartId=1|Electrical=4|PinConglomerate=49|PinLength=20|Location.X=1090|Location.Y=320|Name=A|Designator=2|PinPropagationDelay=0.000000E+000
|RECORD=2|OwnerIndex=1543|OwnerPartId=1|Electrical=4|PinConglomerate=51|PinLength=20|Location.X=1090|Location.Y=300|Name=C|Designator=1|PinPropagationDelay=0.000000E+000
|RECORD=13|OwnerIndex=1543|IsNotAccesible=T|IndexInSheet=2|OwnerPartId=1|Location.X=1100|Location.Y=320|Corner.X=1080|Corner.Y=320|LineWidth=1|Color=16711680
|RECORD=13|OwnerIndex=1543|IsNotAccesible=T|IndexInSheet=3|OwnerPartId=1|Location.X=1100|Location.Y=300|Corner.X=1080|Corner.Y=300|LineWidth=1|Color=16711680
|RECORD=13|OwnerIndex=1543|IsNotAccesible=T|IndexInSheet=4|OwnerPartId=1|Location.X=1100|Location.Y=320|Corner.X=1090|Corner.Y=300|LineWidth=1|Color=16711680
|RECORD=13|OwnerIndex=1543|IsNotAccesible=T|IndexInSheet=5|OwnerPartId=1|Location.X=1080|Location.Y=320|Corner.X=1090|Corner.Y=300|LineWidth=1|Color=16711680
|RECORD=13|OwnerIndex=1543|IsNotAccesible=T|IndexInSheet=6|OwnerPartId=1|Location.X=1102|Location.Y=315|Corner.X=1112|Corner.Y=305|LineWidth=1|Color=16711680
|RECORD=13|OwnerIndex=1543|IsNotAccesible=T|IndexInSheet=7|OwnerPartId=1|Location.X=1112|Location.Y=305|Corner.X=1112|Corner.Y=310|LineWidth=1|Color=16711680
|RECORD=13|OwnerIndex=1543|IsNotAccesible=T|IndexInSheet=8|OwnerPartId=1|Location.X=1112|Location.Y=305|Corner.X=1107|Corner.Y=305|LineWidth=1|Color=16711680
|RECORD=13|OwnerIndex=1543|IsNotAccesible=T|IndexInSheet=9|OwnerPartId=1|Location.X=1098|Location.Y=308|Corner.X=1108|Corner.Y=298|LineWidth=1|Color=16711680
|RECORD=13|OwnerIndex=1543|IsNotAccesible=T|IndexInSheet=10|OwnerPartId=1|Location.X=1108|Location.Y=298|Corner.X=1108|Corner.Y=303|LineWidth=1|Color=16711680
|RECORD=13|OwnerIndex=1543|IsNotAccesible=T|IndexInSheet=11|OwnerPartId=1|Location.X=1108|Location.Y=298|Corner.X=1103|Corner.Y=298|LineWidth=1|Color=16711680
|RECORD=13|OwnerIndex=1543|IsNotAccesible=T|IndexInSheet=12|OwnerPartId=1|Location.X=1090|Location.Y=320|Corner.X=1090|Corner.Y=323|LineWidth=1|Color=16711680
|RECORD=13|OwnerIndex=1543|IsNotAccesible=T|IndexInSheet=13|OwnerPartId=1|Location.X=1090|Location.Y=300|Corner.X=1090|Corner.Y=297|LineWidth=1|Color=16711680
|RECORD=41|OwnerIndex=1543|IndexInSheet=14|OwnerPartId=-1|Location.X=1079|Location.Y=342|Color=8388608|FontID=1|IsHidden=T|Text=14mcd|Name=Luminous Intensity
|RECORD=41|OwnerIndex=1543|IndexInSheet=15|OwnerPartId=-1|Location.X=1079|Location.Y=342|Color=8388608|FontID=1|IsHidden=T|Text=0.6mm|Name=Height
|RECORD=41|OwnerIndex=1543|IndexInSheet=16|OwnerPartId=-1|Location.X=1079|Location.Y=342|Color=8388608|FontID=1|IsHidden=T|Text=20mA|Name=Test Current
|RECORD=41|OwnerIndex=1543|IndexInSheet=17|OwnerPartId=-1|Location.X=1079|Location.Y=342|Color=8388608|FontID=1|IsHidden=T|Text=Yes|Name=RoHS Compliant
|RECORD=41|OwnerIndex=1543|IndexInSheet=18|OwnerPartId=-1|Location.X=1079|Location.Y=342|Color=8388608|FontID=1|IsHidden=T|Text=Lead Free|Name=Lead Free
|RECORD=41|OwnerIndex=1543|IndexInSheet=19|OwnerPartId=-1|Location.X=1079|Location.Y=342|Color=8388608|FontID=1|IsHidden=T|Text=2|Name=Number of Pins
|RECORD=41|OwnerIndex=1543|IndexInSheet=20|OwnerPartId=-1|Location.X=1079|Location.Y=342|Color=8388608|FontID=1|IsHidden=T|Text=Tape and Reel|Name=Packaging
|RECORD=41|OwnerIndex=1543|IndexInSheet=21|OwnerPartId=-1|Location.X=1079|Location.Y=342|Color=8388608|FontID=1|IsHidden=T|Text=0603|Name=Case/Package
|RECORD=41|OwnerIndex=1543|IndexInSheet=22|OwnerPartId=-1|Location.X=1079|Location.Y=342|Color=8388608|FontID=1|IsHidden=T|Text=1.6mm|Name=Length
|RECORD=41|OwnerIndex=1543|IndexInSheet=23|OwnerPartId=-1|Location.X=1079|Location.Y=342|Color=8388608|FontID=1|IsHidden=T|Text=Red|Name=Color
|RECORD=41|OwnerIndex=1543|IndexInSheet=24|OwnerPartId=-1|Location.X=1079|Location.Y=342|Color=8388608|FontID=1|IsHidden=T|Text=85°C|Name=Max Operating Temperature
|RECORD=41|OwnerIndex=1543|IndexInSheet=25|OwnerPartId=-1|Location.X=1079|Location.Y=342|Color=8388608|FontID=1|IsHidden=T|Text=Red|Name=Illumination Color
|RECORD=41|OwnerIndex=1543|IndexInSheet=26|OwnerPartId=-1|Location.X=1079|Location.Y=342|Color=8388608|FontID=1|IsHidden=T|Text=160°|Name=Viewing Angle
|RECORD=41|OwnerIndex=1543|IndexInSheet=27|OwnerPartId=-1|Location.X=1079|Location.Y=342|Color=8388608|FontID=1|IsHidden=T|Text=UL|Name=Approvals
|RECORD=41|OwnerIndex=1543|IndexInSheet=28|OwnerPartId=-1|Location.X=1079|Location.Y=342|Color=8388608|FontID=1|IsHidden=T|Text=1608|Name=Case Code (Metric)
|RECORD=41|OwnerIndex=1543|IndexInSheet=29|OwnerPartId=-1|Location.X=1079|Location.Y=342|Color=8388608|FontID=1|IsHidden=T|Text=0.061inch|Name=Diameter
|RECORD=41|OwnerIndex=1543|IndexInSheet=30|OwnerPartId=-1|Location.X=1079|Location.Y=342|Color=8388608|FontID=1|IsHidden=T|Text=-25°C|Name=Min Operating Temperature
|RECORD=41|OwnerIndex=1543|IndexInSheet=31|OwnerPartId=-1|Location.X=1079|Location.Y=342|Color=8388608|FontID=1|IsHidden=T|Text=Diffused|Name=Lens Style
|RECORD=41|OwnerIndex=1543|IndexInSheet=32|OwnerPartId=-1|Location.X=1079|Location.Y=342|Color=8388608|FontID=1|IsHidden=T|Text=Surface Mount|Name=Mount
|RECORD=41|OwnerIndex=1543|IndexInSheet=33|OwnerPartId=-1|Location.X=1079|Location.Y=342|Color=8388608|FontID=1|IsHidden=T|Text=0.8mm|Name=Width
|RECORD=41|OwnerIndex=1543|IndexInSheet=34|OwnerPartId=-1|Location.X=1079|Location.Y=342|Color=8388608|FontID=1|IsHidden=T|Text=2V|Name=Forward Voltage
|RECORD=41|OwnerIndex=1543|IndexInSheet=35|OwnerPartId=-1|Location.X=1079|Location.Y=342|Color=8388608|FontID=1|IsHidden=T|Text=50mW|Name=Power Dissipation
|RECORD=41|OwnerIndex=1543|IndexInSheet=36|OwnerPartId=-1|Location.X=1079|Location.Y=342|Color=8388608|FontID=1|IsHidden=T|Text=635nm|Name=Dominant Wavelength
|RECORD=41|OwnerIndex=1543|IndexInSheet=37|OwnerPartId=-1|Location.X=1079|Location.Y=342|Color=8388608|FontID=1|IsHidden=T|Text=1|Name=Number of LEDs
|RECORD=41|OwnerIndex=1543|IndexInSheet=38|OwnerPartId=-1|Location.X=1079|Location.Y=342|Color=8388608|FontID=1|IsHidden=T|Text=0603|Name=Case Code (Imperial)
|RECORD=41|OwnerIndex=1543|IndexInSheet=39|OwnerPartId=-1|Location.X=1079|Location.Y=342|Color=8388608|FontID=1|IsHidden=T|Text=Diffused|Name=Lens Transparency
|RECORD=41|OwnerIndex=1543|IndexInSheet=40|OwnerPartId=-1|Location.X=1079|Location.Y=342|Color=8388608|FontID=1|IsHidden=T|Text=635nm|Name=Wavelength
|RECORD=41|OwnerIndex=1543|IndexInSheet=41|OwnerPartId=-1|Location.X=1079|Location.Y=342|Color=8388608|FontID=1|IsHidden=T|Text=White|Name=Lens Color
|RECORD=41|OwnerIndex=1543|IndexInSheet=42|OwnerPartId=-1|Location.X=1079|Location.Y=342|Color=8388608|FontID=1|IsHidden=T|Text=1|Name=Package Quantity
|RECORD=41|OwnerIndex=1543|IndexInSheet=43|OwnerPartId=-1|Location.X=1079|Location.Y=342|Color=8388608|FontID=1|IsHidden=T|Text=20mA|Name=Forward Current
|RECORD=34|OwnerIndex=1543|IndexInSheet=-1|OwnerPartId=-1|Location.X=1113|Location.Y=314|Color=8388608|FontID=1|Text=D24|Name=Designator|ReadOnlyState=1
|RECORD=41|OwnerIndex=1543|IndexInSheet=-1|OwnerPartId=1|Location.X=1113|Location.Y=304|Color=8388608|FontID=1|Text=SML-LX0603IW-TR|Name=Comment
|RECORD=44|OwnerIndex=1543
|RECORD=45|OwnerIndex=1592|IndexInSheet=-1|UseComponentLibrary=T|ModelName=FP-SML-LX0603IW-TR-MFG|ModelType=PCBLIB|DatafileCount=1|ModelDatafileEntity0=FP-SML-LX0603IW-TR-MFG|ModelDatafileKind0=PCBLib|IsCurrent=T|DatalinksLocked=T|DatabaseDatalinksLocked=T
|RECORD=46|OwnerIndex=1593
|RECORD=48|OwnerIndex=1593
|RECORD=1|LibReference=1029c3af85768c4190bb7ad29bc67b5|ComponentDescription=RES SMD 200 OHM 1% 1/10W 0402|PartCount=2|DisplayModeCount=1|IndexInSheet=222|OwnerPartId=-1|Location.X=1090|Location.Y=190|Orientation=1|CurrentPartId=1|LibraryPath=*|SourceLibraryName=Altium Content Vault|TargetFileName=*|AreaColor=11599871|Color=128|PartIDLocked=T|DesignItemId=CMP-2002-00757-2|AllPinCount=2
|RECORD=2|OwnerIndex=1596|OwnerPartId=1|Electrical=4|PinConglomerate=51|PinLength=20|Location.X=1090|Location.Y=210|Name=1|Designator=1|PinPropagationDelay=0.000000E+000
|RECORD=2|OwnerIndex=1596|OwnerPartId=1|Electrical=4|PinConglomerate=49|PinLength=20|Location.X=1090|Location.Y=240|Name=2|Designator=2|PinPropagationDelay=0.000000E+000
|RECORD=13|OwnerIndex=1596|IsNotAccesible=T|IndexInSheet=2|OwnerPartId=1|Location.X=1090|Location.Y=210|Corner.X=1085|Corner.Y=213|LineWidth=1|Color=16711680
|RECORD=13|OwnerIndex=1596|IsNotAccesible=T|IndexInSheet=3|OwnerPartId=1|Location.X=1085|Location.Y=213|Corner.X=1095|Corner.Y=218|LineWidth=1|Color=16711680
|RECORD=13|OwnerIndex=1596|IsNotAccesible=T|IndexInSheet=4|OwnerPartId=1|Location.X=1095|Location.Y=218|Corner.X=1085|Corner.Y=223|LineWidth=1|Color=16711680
|RECORD=13|OwnerIndex=1596|IsNotAccesible=T|IndexInSheet=5|OwnerPartId=1|Location.X=1085|Location.Y=223|Corner.X=1095|Corner.Y=228|LineWidth=1|Color=16711680
|RECORD=13|OwnerIndex=1596|IsNotAccesible=T|IndexInSheet=6|OwnerPartId=1|Location.X=1095|Location.Y=228|Corner.X=1085|Corner.Y=233|LineWidth=1|Color=16711680
|RECORD=13|OwnerIndex=1596|IsNotAccesible=T|IndexInSheet=7|OwnerPartId=1|Location.X=1085|Location.Y=233|Corner.X=1095|Corner.Y=238|LineWidth=1|Color=16711680
|RECORD=13|OwnerIndex=1596|IsNotAccesible=T|IndexInSheet=8|OwnerPartId=1|Location.X=1095|Location.Y=238|Corner.X=1090|Corner.Y=240|LineWidth=1|Color=16711680
|RECORD=13|OwnerIndex=1596|IsNotAccesible=T|IndexInSheet=9|OwnerPartId=1|Location.X=1090|Location.Y=210|Corner.X=1090|Corner.Y=207|LineWidth=1|Color=16711680
|RECORD=13|OwnerIndex=1596|IsNotAccesible=T|IndexInSheet=10|OwnerPartId=1|Location.X=1090|Location.Y=240|Corner.X=1090|Corner.Y=243|LineWidth=1|Color=16711680
|RECORD=41|OwnerIndex=1596|IndexInSheet=11|OwnerPartId=-1|Location.X=1084|Location.Y=262|Color=8388608|FontID=1|IsHidden=T|Text=Yes|Name=RoHS Compliant
|RECORD=41|OwnerIndex=1596|IndexInSheet=12|OwnerPartId=-1|Location.X=1084|Location.Y=262|Color=8388608|FontID=1|IsHidden=T|Text=Tape and Reel|Name=Packaging
|RECORD=41|OwnerIndex=1596|IndexInSheet=13|OwnerPartId=-1|Location.X=1084|Location.Y=262|Color=8388608|FontID=1|IsHidden=T|Text=1005|Name=Case Code (Metric)
|RECORD=41|OwnerIndex=1596|IndexInSheet=14|OwnerPartId=-1|Location.X=1084|Location.Y=262|Color=8388608|FontID=1|IsHidden=T|Text=1|Name=Package Quantity
|RECORD=41|OwnerIndex=1596|IndexInSheet=15|OwnerPartId=-1|Location.X=1084|Location.Y=262|Color=8388608|FontID=1|IsHidden=T|Text=Tin|Name=Contact Plating
|RECORD=41|OwnerIndex=1596|IndexInSheet=16|OwnerPartId=-1|Location.X=1084|Location.Y=262|Color=8388608|FontID=1|IsHidden=T|Text=100mW|Name=Power Rating
|RECORD=41|OwnerIndex=1596|IndexInSheet=17|OwnerPartId=-1|Location.X=1084|Location.Y=262|Color=8388608|FontID=1|IsHidden=T|Text=ERJ|Name=Series
|RECORD=41|OwnerIndex=1596|IndexInSheet=18|OwnerPartId=-1|Location.X=1084|Location.Y=262|Color=8388608|FontID=1|IsHidden=T|Text=Surface Mount|Name=Mount
|RECORD=41|OwnerIndex=1596|IndexInSheet=19|OwnerPartId=-1|Location.X=1084|Location.Y=262|Color=8388608|FontID=1|IsHidden=T|Text=Lead Free|Name=Lead Free
|RECORD=41|OwnerIndex=1596|IndexInSheet=20|OwnerPartId=-1|Location.X=1084|Location.Y=262|Color=8388608|FontID=1|IsHidden=T|Text=-55°C|Name=Min Operating Temperature
|RECORD=41|OwnerIndex=1596|IndexInSheet=21|OwnerPartId=-1|Location.X=1084|Location.Y=262|Color=8388608|FontID=1|IsHidden=T|Text=2|Name=Number of Terminations
|RECORD=41|OwnerIndex=1596|IndexInSheet=22|OwnerPartId=-1|Location.X=1084|Location.Y=262|Color=8388608|FontID=1|IsHidden=T|Text=50V|Name=Voltage Rating (DC)
|RECORD=41|OwnerIndex=1596|IndexInSheet=23|OwnerPartId=-1|Location.X=1084|Location.Y=262|Color=8388608|FontID=1|IsHidden=T|Text=100mW|Name=Max Power Dissipation
|RECORD=41|OwnerIndex=1596|IndexInSheet=24|OwnerPartId=-1|Location.X=1084|Location.Y=262|Color=8388608|FontID=1|IsHidden=T|Text=THICK FILM|Name=Technology
|RECORD=41|OwnerIndex=1596|IndexInSheet=25|OwnerPartId=-1|Location.X=1084|Location.Y=262|Color=8388608|FontID=1|IsHidden=T|Text=200R|Name=Resistance
|RECORD=41|OwnerIndex=1596|IndexInSheet=26|OwnerPartId=-1|Location.X=1084|Location.Y=262|Color=8388608|FontID=1|IsHidden=T|Text=50V|Name=Voltage Rating
|RECORD=41|OwnerIndex=1596|IndexInSheet=27|OwnerPartId=-1|Location.X=1084|Location.Y=262|Color=8388608|FontID=1|IsHidden=T|Text=0402|Name=Case/Package
|RECORD=41|OwnerIndex=1596|IndexInSheet=28|OwnerPartId=-1|Location.X=1084|Location.Y=262|Color=8388608|FontID=1|IsHidden=T|Text=0.02inch|Name=Width
|RECORD=41|OwnerIndex=1596|IndexInSheet=29|OwnerPartId=-1|Location.X=1084|Location.Y=262|Color=8388608|FontID=1|IsHidden=T|Text=SMD/SMT|Name=Termination
|RECORD=41|OwnerIndex=1596|IndexInSheet=30|OwnerPartId=-1|Location.X=1084|Location.Y=262|Color=8388608|FontID=1|IsHidden=T|Text=Not|Name=Military Standard
|RECORD=41|OwnerIndex=1596|IndexInSheet=31|OwnerPartId=-1|Location.X=1084|Location.Y=262|Color=8388608|FontID=1|IsHidden=T|Text=100ppm/°C|Name=Temperature Coefficient
|RECORD=41|OwnerIndex=1596|IndexInSheet=32|OwnerPartId=-1|Location.X=1084|Location.Y=262|Color=8388608|FontID=1|IsHidden=T|Text=0.35mm|Name=Height
|RECORD=41|OwnerIndex=1596|IndexInSheet=33|OwnerPartId=-1|Location.X=1084|Location.Y=262|Color=8388608|FontID=1|IsHidden=T|Text=No|Name=Radiation Hardening
|RECORD=41|OwnerIndex=1596|IndexInSheet=34|OwnerPartId=-1|Location.X=1084|Location.Y=262|Color=8388608|FontID=1|IsHidden=T|Text=1%|Name=Resistance Tolerance
|RECORD=41|OwnerIndex=1596|IndexInSheet=35|OwnerPartId=-1|Location.X=1084|Location.Y=262|Color=8388608|FontID=1|IsHidden=T|Text=1mm|Name=Length
|RECORD=41|OwnerIndex=1596|IndexInSheet=36|OwnerPartId=-1|Location.X=1084|Location.Y=262|Color=8388608|FontID=1|IsHidden=T|Text=No SVHC|Name=REACH SVHC
|RECORD=41|OwnerIndex=1596|IndexInSheet=37|OwnerPartId=-1|Location.X=1084|Location.Y=262|Color=8388608|FontID=1|IsHidden=T|Text=Rectangular|Name=Construction
|RECORD=41|OwnerIndex=1596|IndexInSheet=38|OwnerPartId=-1|Location.X=1084|Location.Y=262|Color=8388608|FontID=1|IsHidden=T|Text=0.5mm|Name=Depth
|RECORD=41|OwnerIndex=1596|IndexInSheet=39|OwnerPartId=-1|Location.X=1084|Location.Y=262|Color=8388608|FontID=1|IsHidden=T|Text=Automotive AEC-Q200|Name=Features
|RECORD=41|OwnerIndex=1596|IndexInSheet=40|OwnerPartId=-1|Location.X=1084|Location.Y=262|Color=8388608|FontID=1|IsHidden=T|Text=Thick Film|Name=Resistor Type
|RECORD=41|OwnerIndex=1596|IndexInSheet=41|OwnerPartId=-1|Location.X=1084|Location.Y=262|Color=8388608|FontID=1|IsHidden=T|Text=0402|Name=Case Code (Imperial)
|RECORD=41|OwnerIndex=1596|IndexInSheet=42|OwnerPartId=-1|Location.X=1084|Location.Y=262|Color=8388608|FontID=1|IsHidden=T|Text=1%|Name=Tolerance
|RECORD=41|OwnerIndex=1596|IndexInSheet=43|OwnerPartId=-1|Location.X=1084|Location.Y=262|Color=8388608|FontID=1|IsHidden=T|Text=0402|Name=Size Code
|RECORD=41|OwnerIndex=1596|IndexInSheet=44|OwnerPartId=-1|Location.X=1084|Location.Y=262|Color=8388608|FontID=1|IsHidden=T|Text=155°C|Name=Max Operating Temperature
|RECORD=34|OwnerIndex=1596|IndexInSheet=-1|OwnerPartId=-1|Location.X=1096|Location.Y=234|Color=8388608|FontID=1|Text=R94|Name=Designator|ReadOnlyState=1
|RECORD=41|OwnerIndex=1596|IndexInSheet=-1|OwnerPartId=1|Location.X=1096|Location.Y=224|Color=8388608|FontID=1|Text=200_1%_0402|Name=Comment
|RECORD=44|OwnerIndex=1596
|RECORD=45|OwnerIndex=1646|IndexInSheet=-1|UseComponentLibrary=T|ModelName=FP-ERJ2RK-IPC_A|ModelType=PCBLIB|DatafileCount=1|ModelDatafileEntity0=FP-ERJ2RK-IPC_A|ModelDatafileKind0=PCBLib|IsCurrent=T|DatalinksLocked=T|DatabaseDatalinksLocked=T
|RECORD=46|OwnerIndex=1647
|RECORD=48|OwnerIndex=1647
|RECORD=45|OwnerIndex=1646|IndexInSheet=-1|UseComponentLibrary=T|ModelName=FP-ERJ2RK-IPC_C|ModelType=PCBLIB|DatafileCount=1|ModelDatafileEntity0=FP-ERJ2RK-IPC_C|ModelDatafileKind0=PCBLib|DatalinksLocked=T|DatabaseDatalinksLocked=T
|RECORD=46|OwnerIndex=1650
|RECORD=48|OwnerIndex=1650
|RECORD=45|OwnerIndex=1646|IndexInSheet=-1|UseComponentLibrary=T|ModelName=FP-ERJ2RK-MFG|ModelType=PCBLIB|DatafileCount=1|ModelDatafileEntity0=FP-ERJ2RK-MFG|ModelDatafileKind0=PCBLib|DatalinksLocked=T|DatabaseDatalinksLocked=T
|RECORD=46|OwnerIndex=1653
|RECORD=48|OwnerIndex=1653
|RECORD=45|OwnerIndex=1646|IndexInSheet=-1|UseComponentLibrary=T|ModelName=FP-ERJ2RK-IPC_B|ModelType=PCBLIB|DatafileCount=1|ModelDatafileEntity0=FP-ERJ2RK-IPC_B|ModelDatafileKind0=PCBLib|DatalinksLocked=T|DatabaseDatalinksLocked=T
|RECORD=46|OwnerIndex=1656
|RECORD=48|OwnerIndex=1656
|RECORD=17|IndexInSheet=223|OwnerPartId=-1|Style=1|ShowNetName=T|Location.X=1070|Location.Y=160|Orientation=2|Color=255|FontID=1|Text=DIP_SW_PPS_SEL|IsCrossSheetConnector=T
|RECORD=27|IndexInSheet=224|OwnerPartId=-1|LineWidth=1|Color=8388608|LocationCount=3|X1=1070|Y1=160|X2=1090|Y2=160|X3=1090|Y3=190
|RECORD=27|IndexInSheet=225|OwnerPartId=-1|LineWidth=1|Color=8388608|LocationCount=3|X1=1090|Y1=520|X2=1180|Y2=520|X3=1200|Y3=520
|RECORD=27|IndexInSheet=226|OwnerPartId=-1|LineWidth=1|Color=8388608|LocationCount=4|X1=1200|Y1=490|X2=1180|Y2=490|X3=1180|Y3=470|X4=1180|Y4=460
|RECORD=27|IndexInSheet=227|OwnerPartId=-1|LineWidth=1|Color=8388608|LocationCount=3|X1=1140|Y1=650|X2=1140|Y2=680|X3=1140|Y3=700
|RECORD=17|IndexInSheet=228|OwnerPartId=-1|ShowNetName=T|Location.X=1340|Location.Y=350|Orientation=1|Color=128|FontID=1|Text=+3.3V
|RECORD=27|IndexInSheet=229|OwnerPartId=-1|LineWidth=1|Color=8388608|LocationCount=2|X1=1340|Y1=280|X2=1340|Y2=260
|RECORD=27|IndexInSheet=230|OwnerPartId=-1|LineWidth=1|Color=8388608|LocationCount=2|X1=1340|Y1=340|X2=1340|Y2=350
|RECORD=1|LibReference=8706943c75ba83719d021d2fdc84c58|ComponentDescription=LED RED DIFFUSED SMD|PartCount=2|DisplayModeCount=1|IndexInSheet=231|OwnerPartId=-1|Location.X=1340|Location.Y=340|Orientation=3|CurrentPartId=1|LibraryPath=*|SourceLibraryName=Altium Content Vault|TargetFileName=*|AreaColor=11599871|Color=128|PartIDLocked=T|DesignItemId=CMP-57192-000012-1|AllPinCount=2
|RECORD=2|OwnerIndex=1667|OwnerPartId=1|Electrical=4|PinConglomerate=49|PinLength=20|Location.X=1340|Location.Y=320|Name=A|Designator=2|PinPropagationDelay=0.000000E+000
|RECORD=2|OwnerIndex=1667|OwnerPartId=1|Electrical=4|PinConglomerate=51|PinLength=20|Location.X=1340|Location.Y=300|Name=C|Designator=1|PinPropagationDelay=0.000000E+000
|RECORD=13|OwnerIndex=1667|IsNotAccesible=T|IndexInSheet=2|OwnerPartId=1|Location.X=1350|Location.Y=320|Corner.X=1330|Corner.Y=320|LineWidth=1|Color=16711680
|RECORD=13|OwnerIndex=1667|IsNotAccesible=T|IndexInSheet=3|OwnerPartId=1|Location.X=1350|Location.Y=300|Corner.X=1330|Corner.Y=300|LineWidth=1|Color=16711680
|RECORD=13|OwnerIndex=1667|IsNotAccesible=T|IndexInSheet=4|OwnerPartId=1|Location.X=1350|Location.Y=320|Corner.X=1340|Corner.Y=300|LineWidth=1|Color=16711680
|RECORD=13|OwnerIndex=1667|IsNotAccesible=T|IndexInSheet=5|OwnerPartId=1|Location.X=1330|Location.Y=320|Corner.X=1340|Corner.Y=300|LineWidth=1|Color=16711680
|RECORD=13|OwnerIndex=1667|IsNotAccesible=T|IndexInSheet=6|OwnerPartId=1|Location.X=1352|Location.Y=315|Corner.X=1362|Corner.Y=305|LineWidth=1|Color=16711680
|RECORD=13|OwnerIndex=1667|IsNotAccesible=T|IndexInSheet=7|OwnerPartId=1|Location.X=1362|Location.Y=305|Corner.X=1362|Corner.Y=310|LineWidth=1|Color=16711680
|RECORD=13|OwnerIndex=1667|IsNotAccesible=T|IndexInSheet=8|OwnerPartId=1|Location.X=1362|Location.Y=305|Corner.X=1357|Corner.Y=305|LineWidth=1|Color=16711680
|RECORD=13|OwnerIndex=1667|IsNotAccesible=T|IndexInSheet=9|OwnerPartId=1|Location.X=1348|Location.Y=308|Corner.X=1358|Corner.Y=298|LineWidth=1|Color=16711680
|RECORD=13|OwnerIndex=1667|IsNotAccesible=T|IndexInSheet=10|OwnerPartId=1|Location.X=1358|Location.Y=298|Corner.X=1358|Corner.Y=303|LineWidth=1|Color=16711680
|RECORD=13|OwnerIndex=1667|IsNotAccesible=T|IndexInSheet=11|OwnerPartId=1|Location.X=1358|Location.Y=298|Corner.X=1353|Corner.Y=298|LineWidth=1|Color=16711680
|RECORD=13|OwnerIndex=1667|IsNotAccesible=T|IndexInSheet=12|OwnerPartId=1|Location.X=1340|Location.Y=320|Corner.X=1340|Corner.Y=323|LineWidth=1|Color=16711680
|RECORD=13|OwnerIndex=1667|IsNotAccesible=T|IndexInSheet=13|OwnerPartId=1|Location.X=1340|Location.Y=300|Corner.X=1340|Corner.Y=297|LineWidth=1|Color=16711680
|RECORD=41|OwnerIndex=1667|IndexInSheet=14|OwnerPartId=-1|Location.X=1329|Location.Y=342|Color=8388608|FontID=1|IsHidden=T|Text=14mcd|Name=Luminous Intensity
|RECORD=41|OwnerIndex=1667|IndexInSheet=15|OwnerPartId=-1|Location.X=1329|Location.Y=342|Color=8388608|FontID=1|IsHidden=T|Text=0.6mm|Name=Height
|RECORD=41|OwnerIndex=1667|IndexInSheet=16|OwnerPartId=-1|Location.X=1329|Location.Y=342|Color=8388608|FontID=1|IsHidden=T|Text=20mA|Name=Test Current
|RECORD=41|OwnerIndex=1667|IndexInSheet=17|OwnerPartId=-1|Location.X=1329|Location.Y=342|Color=8388608|FontID=1|IsHidden=T|Text=Yes|Name=RoHS Compliant
|RECORD=41|OwnerIndex=1667|IndexInSheet=18|OwnerPartId=-1|Location.X=1329|Location.Y=342|Color=8388608|FontID=1|IsHidden=T|Text=Lead Free|Name=Lead Free
|RECORD=41|OwnerIndex=1667|IndexInSheet=19|OwnerPartId=-1|Location.X=1329|Location.Y=342|Color=8388608|FontID=1|IsHidden=T|Text=2|Name=Number of Pins
|RECORD=41|OwnerIndex=1667|IndexInSheet=20|OwnerPartId=-1|Location.X=1329|Location.Y=342|Color=8388608|FontID=1|IsHidden=T|Text=Tape and Reel|Name=Packaging
|RECORD=41|OwnerIndex=1667|IndexInSheet=21|OwnerPartId=-1|Location.X=1329|Location.Y=342|Color=8388608|FontID=1|IsHidden=T|Text=0603|Name=Case/Package
|RECORD=41|OwnerIndex=1667|IndexInSheet=22|OwnerPartId=-1|Location.X=1329|Location.Y=342|Color=8388608|FontID=1|IsHidden=T|Text=1.6mm|Name=Length
|RECORD=41|OwnerIndex=1667|IndexInSheet=23|OwnerPartId=-1|Location.X=1329|Location.Y=342|Color=8388608|FontID=1|IsHidden=T|Text=Red|Name=Color
|RECORD=41|OwnerIndex=1667|IndexInSheet=24|OwnerPartId=-1|Location.X=1329|Location.Y=342|Color=8388608|FontID=1|IsHidden=T|Text=85°C|Name=Max Operating Temperature
|RECORD=41|OwnerIndex=1667|IndexInSheet=25|OwnerPartId=-1|Location.X=1329|Location.Y=342|Color=8388608|FontID=1|IsHidden=T|Text=Red|Name=Illumination Color
|RECORD=41|OwnerIndex=1667|IndexInSheet=26|OwnerPartId=-1|Location.X=1329|Location.Y=342|Color=8388608|FontID=1|IsHidden=T|Text=160°|Name=Viewing Angle
|RECORD=41|OwnerIndex=1667|IndexInSheet=27|OwnerPartId=-1|Location.X=1329|Location.Y=342|Color=8388608|FontID=1|IsHidden=T|Text=UL|Name=Approvals
|RECORD=41|OwnerIndex=1667|IndexInSheet=28|OwnerPartId=-1|Location.X=1329|Location.Y=342|Color=8388608|FontID=1|IsHidden=T|Text=1608|Name=Case Code (Metric)
|RECORD=41|OwnerIndex=1667|IndexInSheet=29|OwnerPartId=-1|Location.X=1329|Location.Y=342|Color=8388608|FontID=1|IsHidden=T|Text=0.061inch|Name=Diameter
|RECORD=41|OwnerIndex=1667|IndexInSheet=30|OwnerPartId=-1|Location.X=1329|Location.Y=342|Color=8388608|FontID=1|IsHidden=T|Text=-25°C|Name=Min Operating Temperature
|RECORD=41|OwnerIndex=1667|IndexInSheet=31|OwnerPartId=-1|Location.X=1329|Location.Y=342|Color=8388608|FontID=1|IsHidden=T|Text=Diffused|Name=Lens Style
|RECORD=41|OwnerIndex=1667|IndexInSheet=32|OwnerPartId=-1|Location.X=1329|Location.Y=342|Color=8388608|FontID=1|IsHidden=T|Text=Surface Mount|Name=Mount
|RECORD=41|OwnerIndex=1667|IndexInSheet=33|OwnerPartId=-1|Location.X=1329|Location.Y=342|Color=8388608|FontID=1|IsHidden=T|Text=0.8mm|Name=Width
|RECORD=41|OwnerIndex=1667|IndexInSheet=34|OwnerPartId=-1|Location.X=1329|Location.Y=342|Color=8388608|FontID=1|IsHidden=T|Text=2V|Name=Forward Voltage
|RECORD=41|OwnerIndex=1667|IndexInSheet=35|OwnerPartId=-1|Location.X=1329|Location.Y=342|Color=8388608|FontID=1|IsHidden=T|Text=50mW|Name=Power Dissipation
|RECORD=41|OwnerIndex=1667|IndexInSheet=36|OwnerPartId=-1|Location.X=1329|Location.Y=342|Color=8388608|FontID=1|IsHidden=T|Text=635nm|Name=Dominant Wavelength
|RECORD=41|OwnerIndex=1667|IndexInSheet=37|OwnerPartId=-1|Location.X=1329|Location.Y=342|Color=8388608|FontID=1|IsHidden=T|Text=1|Name=Number of LEDs
|RECORD=41|OwnerIndex=1667|IndexInSheet=38|OwnerPartId=-1|Location.X=1329|Location.Y=342|Color=8388608|FontID=1|IsHidden=T|Text=0603|Name=Case Code (Imperial)
|RECORD=41|OwnerIndex=1667|IndexInSheet=39|OwnerPartId=-1|Location.X=1329|Location.Y=342|Color=8388608|FontID=1|IsHidden=T|Text=Diffused|Name=Lens Transparency
|RECORD=41|OwnerIndex=1667|IndexInSheet=40|OwnerPartId=-1|Location.X=1329|Location.Y=342|Color=8388608|FontID=1|IsHidden=T|Text=635nm|Name=Wavelength
|RECORD=41|OwnerIndex=1667|IndexInSheet=41|OwnerPartId=-1|Location.X=1329|Location.Y=342|Color=8388608|FontID=1|IsHidden=T|Text=White|Name=Lens Color
|RECORD=41|OwnerIndex=1667|IndexInSheet=42|OwnerPartId=-1|Location.X=1329|Location.Y=342|Color=8388608|FontID=1|IsHidden=T|Text=1|Name=Package Quantity
|RECORD=41|OwnerIndex=1667|IndexInSheet=43|OwnerPartId=-1|Location.X=1329|Location.Y=342|Color=8388608|FontID=1|IsHidden=T|Text=20mA|Name=Forward Current
|RECORD=34|OwnerIndex=1667|IndexInSheet=-1|OwnerPartId=-1|Location.X=1363|Location.Y=314|Color=8388608|FontID=1|Text=D25|Name=Designator|ReadOnlyState=1
|RECORD=41|OwnerIndex=1667|IndexInSheet=-1|OwnerPartId=1|Location.X=1363|Location.Y=304|Color=8388608|FontID=1|Text=SML-LX0603IW-TR|Name=Comment
|RECORD=44|OwnerIndex=1667
|RECORD=45|OwnerIndex=1716|IndexInSheet=-1|UseComponentLibrary=T|ModelName=FP-SML-LX0603IW-TR-MFG|ModelType=PCBLIB|DatafileCount=1|ModelDatafileEntity0=FP-SML-LX0603IW-TR-MFG|ModelDatafileKind0=PCBLib|IsCurrent=T|DatalinksLocked=T|DatabaseDatalinksLocked=T
|RECORD=46|OwnerIndex=1717
|RECORD=48|OwnerIndex=1717
|RECORD=1|LibReference=1029c3af85768c4190bb7ad29bc67b5|ComponentDescription=RES SMD 200 OHM 1% 1/10W 0402|PartCount=2|DisplayModeCount=1|IndexInSheet=232|OwnerPartId=-1|Location.X=1340|Location.Y=190|Orientation=1|CurrentPartId=1|LibraryPath=*|SourceLibraryName=Altium Content Vault|TargetFileName=*|AreaColor=11599871|Color=128|PartIDLocked=T|DesignItemId=CMP-2002-00757-2|AllPinCount=2
|RECORD=2|OwnerIndex=1720|OwnerPartId=1|Electrical=4|PinConglomerate=51|PinLength=20|Location.X=1340|Location.Y=210|Name=1|Designator=1|PinPropagationDelay=0.000000E+000
|RECORD=2|OwnerIndex=1720|OwnerPartId=1|Electrical=4|PinConglomerate=49|PinLength=20|Location.X=1340|Location.Y=240|Name=2|Designator=2|PinPropagationDelay=0.000000E+000
|RECORD=13|OwnerIndex=1720|IsNotAccesible=T|IndexInSheet=2|OwnerPartId=1|Location.X=1340|Location.Y=210|Corner.X=1335|Corner.Y=213|LineWidth=1|Color=16711680
|RECORD=13|OwnerIndex=1720|IsNotAccesible=T|IndexInSheet=3|OwnerPartId=1|Location.X=1335|Location.Y=213|Corner.X=1345|Corner.Y=218|LineWidth=1|Color=16711680
|RECORD=13|OwnerIndex=1720|IsNotAccesible=T|IndexInSheet=4|OwnerPartId=1|Location.X=1345|Location.Y=218|Corner.X=1335|Corner.Y=223|LineWidth=1|Color=16711680
|RECORD=13|OwnerIndex=1720|IsNotAccesible=T|IndexInSheet=5|OwnerPartId=1|Location.X=1335|Location.Y=223|Corner.X=1345|Corner.Y=228|LineWidth=1|Color=16711680
|RECORD=13|OwnerIndex=1720|IsNotAccesible=T|IndexInSheet=6|OwnerPartId=1|Location.X=1345|Location.Y=228|Corner.X=1335|Corner.Y=233|LineWidth=1|Color=16711680
|RECORD=13|OwnerIndex=1720|IsNotAccesible=T|IndexInSheet=7|OwnerPartId=1|Location.X=1335|Location.Y=233|Corner.X=1345|Corner.Y=238|LineWidth=1|Color=16711680
|RECORD=13|OwnerIndex=1720|IsNotAccesible=T|IndexInSheet=8|OwnerPartId=1|Location.X=1345|Location.Y=238|Corner.X=1340|Corner.Y=240|LineWidth=1|Color=16711680
|RECORD=13|OwnerIndex=1720|IsNotAccesible=T|IndexInSheet=9|OwnerPartId=1|Location.X=1340|Location.Y=210|Corner.X=1340|Corner.Y=207|LineWidth=1|Color=16711680
|RECORD=13|OwnerIndex=1720|IsNotAccesible=T|IndexInSheet=10|OwnerPartId=1|Location.X=1340|Location.Y=240|Corner.X=1340|Corner.Y=243|LineWidth=1|Color=16711680
|RECORD=41|OwnerIndex=1720|IndexInSheet=11|OwnerPartId=-1|Location.X=1334|Location.Y=262|Color=8388608|FontID=1|IsHidden=T|Text=Yes|Name=RoHS Compliant
|RECORD=41|OwnerIndex=1720|IndexInSheet=12|OwnerPartId=-1|Location.X=1334|Location.Y=262|Color=8388608|FontID=1|IsHidden=T|Text=Tape and Reel|Name=Packaging
|RECORD=41|OwnerIndex=1720|IndexInSheet=13|OwnerPartId=-1|Location.X=1334|Location.Y=262|Color=8388608|FontID=1|IsHidden=T|Text=1005|Name=Case Code (Metric)
|RECORD=41|OwnerIndex=1720|IndexInSheet=14|OwnerPartId=-1|Location.X=1334|Location.Y=262|Color=8388608|FontID=1|IsHidden=T|Text=1|Name=Package Quantity
|RECORD=41|OwnerIndex=1720|IndexInSheet=15|OwnerPartId=-1|Location.X=1334|Location.Y=262|Color=8388608|FontID=1|IsHidden=T|Text=Tin|Name=Contact Plating
|RECORD=41|OwnerIndex=1720|IndexInSheet=16|OwnerPartId=-1|Location.X=1334|Location.Y=262|Color=8388608|FontID=1|IsHidden=T|Text=100mW|Name=Power Rating
|RECORD=41|OwnerIndex=1720|IndexInSheet=17|OwnerPartId=-1|Location.X=1334|Location.Y=262|Color=8388608|FontID=1|IsHidden=T|Text=ERJ|Name=Series
|RECORD=41|OwnerIndex=1720|IndexInSheet=18|OwnerPartId=-1|Location.X=1334|Location.Y=262|Color=8388608|FontID=1|IsHidden=T|Text=Surface Mount|Name=Mount
|RECORD=41|OwnerIndex=1720|IndexInSheet=19|OwnerPartId=-1|Location.X=1334|Location.Y=262|Color=8388608|FontID=1|IsHidden=T|Text=Lead Free|Name=Lead Free
|RECORD=41|OwnerIndex=1720|IndexInSheet=20|OwnerPartId=-1|Location.X=1334|Location.Y=262|Color=8388608|FontID=1|IsHidden=T|Text=-55°C|Name=Min Operating Temperature
|RECORD=41|OwnerIndex=1720|IndexInSheet=21|OwnerPartId=-1|Location.X=1334|Location.Y=262|Color=8388608|FontID=1|IsHidden=T|Text=2|Name=Number of Terminations
|RECORD=41|OwnerIndex=1720|IndexInSheet=22|OwnerPartId=-1|Location.X=1334|Location.Y=262|Color=8388608|FontID=1|IsHidden=T|Text=50V|Name=Voltage Rating (DC)
|RECORD=41|OwnerIndex=1720|IndexInSheet=23|OwnerPartId=-1|Location.X=1334|Location.Y=262|Color=8388608|FontID=1|IsHidden=T|Text=100mW|Name=Max Power Dissipation
|RECORD=41|OwnerIndex=1720|IndexInSheet=24|OwnerPartId=-1|Location.X=1334|Location.Y=262|Color=8388608|FontID=1|IsHidden=T|Text=THICK FILM|Name=Technology
|RECORD=41|OwnerIndex=1720|IndexInSheet=25|OwnerPartId=-1|Location.X=1334|Location.Y=262|Color=8388608|FontID=1|IsHidden=T|Text=200R|Name=Resistance
|RECORD=41|OwnerIndex=1720|IndexInSheet=26|OwnerPartId=-1|Location.X=1334|Location.Y=262|Color=8388608|FontID=1|IsHidden=T|Text=50V|Name=Voltage Rating
|RECORD=41|OwnerIndex=1720|IndexInSheet=27|OwnerPartId=-1|Location.X=1334|Location.Y=262|Color=8388608|FontID=1|IsHidden=T|Text=0402|Name=Case/Package
|RECORD=41|OwnerIndex=1720|IndexInSheet=28|OwnerPartId=-1|Location.X=1334|Location.Y=262|Color=8388608|FontID=1|IsHidden=T|Text=0.02inch|Name=Width
|RECORD=41|OwnerIndex=1720|IndexInSheet=29|OwnerPartId=-1|Location.X=1334|Location.Y=262|Color=8388608|FontID=1|IsHidden=T|Text=SMD/SMT|Name=Termination
|RECORD=41|OwnerIndex=1720|IndexInSheet=30|OwnerPartId=-1|Location.X=1334|Location.Y=262|Color=8388608|FontID=1|IsHidden=T|Text=Not|Name=Military Standard
|RECORD=41|OwnerIndex=1720|IndexInSheet=31|OwnerPartId=-1|Location.X=1334|Location.Y=262|Color=8388608|FontID=1|IsHidden=T|Text=100ppm/°C|Name=Temperature Coefficient
|RECORD=41|OwnerIndex=1720|IndexInSheet=32|OwnerPartId=-1|Location.X=1334|Location.Y=262|Color=8388608|FontID=1|IsHidden=T|Text=0.35mm|Name=Height
|RECORD=41|OwnerIndex=1720|IndexInSheet=33|OwnerPartId=-1|Location.X=1334|Location.Y=262|Color=8388608|FontID=1|IsHidden=T|Text=No|Name=Radiation Hardening
|RECORD=41|OwnerIndex=1720|IndexInSheet=34|OwnerPartId=-1|Location.X=1334|Location.Y=262|Color=8388608|FontID=1|IsHidden=T|Text=1%|Name=Resistance Tolerance
|RECORD=41|OwnerIndex=1720|IndexInSheet=35|OwnerPartId=-1|Location.X=1334|Location.Y=262|Color=8388608|FontID=1|IsHidden=T|Text=1mm|Name=Length
|RECORD=41|OwnerIndex=1720|IndexInSheet=36|OwnerPartId=-1|Location.X=1334|Location.Y=262|Color=8388608|FontID=1|IsHidden=T|Text=No SVHC|Name=REACH SVHC
|RECORD=41|OwnerIndex=1720|IndexInSheet=37|OwnerPartId=-1|Location.X=1334|Location.Y=262|Color=8388608|FontID=1|IsHidden=T|Text=Rectangular|Name=Construction
|RECORD=41|OwnerIndex=1720|IndexInSheet=38|OwnerPartId=-1|Location.X=1334|Location.Y=262|Color=8388608|FontID=1|IsHidden=T|Text=0.5mm|Name=Depth
|RECORD=41|OwnerIndex=1720|IndexInSheet=39|OwnerPartId=-1|Location.X=1334|Location.Y=262|Color=8388608|FontID=1|IsHidden=T|Text=Automotive AEC-Q200|Name=Features
|RECORD=41|OwnerIndex=1720|IndexInSheet=40|OwnerPartId=-1|Location.X=1334|Location.Y=262|Color=8388608|FontID=1|IsHidden=T|Text=Thick Film|Name=Resistor Type
|RECORD=41|OwnerIndex=1720|IndexInSheet=41|OwnerPartId=-1|Location.X=1334|Location.Y=262|Color=8388608|FontID=1|IsHidden=T|Text=0402|Name=Case Code (Imperial)
|RECORD=41|OwnerIndex=1720|IndexInSheet=42|OwnerPartId=-1|Location.X=1334|Location.Y=262|Color=8388608|FontID=1|IsHidden=T|Text=1%|Name=Tolerance
|RECORD=41|OwnerIndex=1720|IndexInSheet=43|OwnerPartId=-1|Location.X=1334|Location.Y=262|Color=8388608|FontID=1|IsHidden=T|Text=0402|Name=Size Code
|RECORD=41|OwnerIndex=1720|IndexInSheet=44|OwnerPartId=-1|Location.X=1334|Location.Y=262|Color=8388608|FontID=1|IsHidden=T|Text=155°C|Name=Max Operating Temperature
|RECORD=34|OwnerIndex=1720|IndexInSheet=-1|OwnerPartId=-1|Location.X=1346|Location.Y=234|Color=8388608|FontID=1|Text=R95|Name=Designator|ReadOnlyState=1
|RECORD=41|OwnerIndex=1720|IndexInSheet=-1|OwnerPartId=1|Location.X=1346|Location.Y=224|Color=8388608|FontID=1|Text=200_1%_0402|Name=Comment
|RECORD=44|OwnerIndex=1720
|RECORD=45|OwnerIndex=1770|IndexInSheet=-1|UseComponentLibrary=T|ModelName=FP-ERJ2RK-IPC_A|ModelType=PCBLIB|DatafileCount=1|ModelDatafileEntity0=FP-ERJ2RK-IPC_A|ModelDatafileKind0=PCBLib|IsCurrent=T|DatalinksLocked=T|DatabaseDatalinksLocked=T
|RECORD=46|OwnerIndex=1771
|RECORD=48|OwnerIndex=1771
|RECORD=45|OwnerIndex=1770|IndexInSheet=-1|UseComponentLibrary=T|ModelName=FP-ERJ2RK-IPC_C|ModelType=PCBLIB|DatafileCount=1|ModelDatafileEntity0=FP-ERJ2RK-IPC_C|ModelDatafileKind0=PCBLib|DatalinksLocked=T|DatabaseDatalinksLocked=T
|RECORD=46|OwnerIndex=1774
|RECORD=48|OwnerIndex=1774
|RECORD=45|OwnerIndex=1770|IndexInSheet=-1|UseComponentLibrary=T|ModelName=FP-ERJ2RK-MFG|ModelType=PCBLIB|DatafileCount=1|ModelDatafileEntity0=FP-ERJ2RK-MFG|ModelDatafileKind0=PCBLib|DatalinksLocked=T|DatabaseDatalinksLocked=T
|RECORD=46|OwnerIndex=1777
|RECORD=48|OwnerIndex=1777
|RECORD=45|OwnerIndex=1770|IndexInSheet=-1|UseComponentLibrary=T|ModelName=FP-ERJ2RK-IPC_B|ModelType=PCBLIB|DatafileCount=1|ModelDatafileEntity0=FP-ERJ2RK-IPC_B|ModelDatafileKind0=PCBLib|DatalinksLocked=T|DatabaseDatalinksLocked=T
|RECORD=46|OwnerIndex=1780
|RECORD=48|OwnerIndex=1780
|RECORD=27|IndexInSheet=233|OwnerPartId=-1|LineWidth=1|Color=8388608|LocationCount=3|X1=1320|Y1=160|X2=1340|Y2=160|X3=1340|Y3=190
|RECORD=17|IndexInSheet=234|OwnerPartId=-1|ShowNetName=T|Location.X=1320|Location.Y=160|Orientation=2|Color=255|FontID=1|Text=DIP_SW_UART_SEL|IsCrossSheetConnector=T
|RECORD=4|IndexInSheet=235|OwnerPartId=-1|Location.X=1200|Location.Y=370|Color=8388608|FontID=1|Text=Status LEDs
|RECORD=4|IndexInSheet=236|OwnerPartId=-1|Location.X=50|Location.Y=580|Color=8388608|FontID=1|Text=UART_SEL = 0 for FTDI <-> GPS2, 1 for FTDI <-> FPGA and FPGA <-> GPS2
|RECORD=4|IndexInSheet=237|OwnerPartId=-1|Location.X=80|Location.Y=570|Color=8388608|FontID=1|Text=PPS_SEL = 0 for Single Ended PPS, 1 for Differential PPS (SA53)
|RECORD=4|IndexInSheet=238|OwnerPartId=-1|Location.X=920|Location.Y=140|Color=8388608|FontID=1|Text=PPS_SEL = 0 for Single Ended PPS, 1 for Differential PPS (SA53)
|RECORD=4|IndexInSheet=239|OwnerPartId=-1|Location.X=1180|Location.Y=140|Color=8388608|FontID=1|Text=UART_SEL = 0 for FTDI <-> GPS2, 1 for FTDI <-> FPGA and FPGA <-> GPS2
|RECORD=43|IndexInSheet=240|OwnerPartId=-1|Location.X=250|Location.Y=810|Color=255|Name=DIFFPAIR
|RECORD=41|OwnerIndex=1790|OwnerPartId=-1|Location.X=250|Location.Y=810|Color=8388608|FontID=1|IsHidden=T|Text=True|Name=DifferentialPair
|RECORD=43|IndexInSheet=241|OwnerPartId=-1|Location.X=250|Location.Y=830|Color=255|Name=DIFFPAIR
|RECORD=41|OwnerIndex=1792|OwnerPartId=-1|Location.X=250|Location.Y=830|Color=8388608|FontID=1|IsHidden=T|Text=True|Name=DifferentialPair
|RECORD=43|IndexInSheet=242|OwnerPartId=-1|Location.X=560|Location.Y=820|Color=255|Name=DIFFPAIR
|RECORD=41|OwnerIndex=1794|OwnerPartId=-1|Location.X=560|Location.Y=820|Color=8388608|FontID=1|IsHidden=T|Text=True|Name=DifferentialPair
|RECORD=43|IndexInSheet=243|OwnerPartId=-1|Location.X=560|Location.Y=810|Color=255|Name=DIFFPAIR
|RECORD=41|OwnerIndex=1796|OwnerPartId=-1|Location.X=560|Location.Y=810|Color=8388608|FontID=1|IsHidden=T|Text=True|Name=DifferentialPair
|RECORD=1|LibReference=RES|PartCount=2|DisplayModeCount=2|IndexInSheet=244|OwnerPartId=-1|Location.X=780|Location.Y=580|CurrentPartId=1|SourceLibraryName=Altium Content Vault|TargetFileName=*|AreaColor=11599871|Color=128|PartIDLocked=F|DesignItemId=CMP-2002-08434-1|AllPinCount=2|ComponentKindVersion2=5
|RECORD=2|OwnerIndex=1798|OwnerPartId=1|OwnerPartDisplayMode=1|FormalType=1|Electrical=4|PinConglomerate=32|PinLength=10|Location.X=800|Location.Y=570|Name=2|Designator=2|PinPropagationDelay=0.000000E+000
|RECORD=2|OwnerIndex=1798|OwnerPartId=1|OwnerPartDisplayMode=1|FormalType=1|Electrical=4|PinConglomerate=34|PinLength=10|Location.X=780|Location.Y=570|Name=1|Designator=1|PinPropagationDelay=0.000000E+000
|RECORD=14|OwnerIndex=1798|IsNotAccesible=T|IndexInSheet=2|OwnerPartId=1|OwnerPartDisplayMode=1|Location.X=780|Location.Y=566|Corner.X=800|Corner.Y=574|LineWidth=1|Color=16711680|AreaColor=11599871
|RECORD=2|OwnerIndex=1798|OwnerPartId=1|FormalType=1|Electrical=4|PinConglomerate=32|PinLength=10|Location.X=800|Location.Y=570|Name=2|Designator=2|PinPropagationDelay=0.000000E+000
|RECORD=2|OwnerIndex=1798|OwnerPartId=1|FormalType=1|Electrical=4|PinConglomerate=34|PinLength=10|Location.X=780|Location.Y=570|Name=1|Designator=1|PinPropagationDelay=0.000000E+000
|RECORD=6|OwnerIndex=1798|IsNotAccesible=T|IndexInSheet=5|OwnerPartId=1|LineWidth=1|Color=16711680|LocationCount=10|X1=800|Y1=570|X2=796|Y2=570|X3=795|Y3=568|X4=793|Y4=572|X5=791|Y5=568|X6=789|Y6=572|X7=787|Y7=568|X8=785|Y8=572|X9=784|Y9=570|X10=780|Y10=570
|RECORD=41|OwnerIndex=1798|IndexInSheet=6|OwnerPartId=-1|Location.X=768|Location.Y=583|Color=8388608|FontID=1|IsHidden=T|Text=CRCW040227R0FKED|Name=Part Number
|RECORD=41|OwnerIndex=1798|IndexInSheet=7|OwnerPartId=-1|Location.X=768|Location.Y=583|Color=8388608|FontID=1|IsHidden=T|Text=Vishay Dale|Name=Manufacturer
|RECORD=34|OwnerIndex=1798|IndexInSheet=-1|OwnerPartId=-1|Location.X=760|Location.Y=570|Color=8388608|FontID=1|Text=R102|Name=Designator|ReadOnlyState=1
|RECORD=41|OwnerIndex=1798|IndexInSheet=-1|OwnerPartId=-1|Location.X=780|Location.Y=570|Color=8388608|FontID=1|Text=DNI_27_1%_0402|Name=Comment
|RECORD=44|OwnerIndex=1798
|RECORD=45|OwnerIndex=1813|IndexInSheet=-1|Description=Chip Resistor, 2-Leads, Body 1.00x0.50mm, IPC Medium Density|UseComponentLibrary=T|ModelName=RESC1005X40X25NL05T05|ModelType=PCBLIB|DatafileCount=1|ModelDatafileEntity0=RESC1005X40X25NL05T05|ModelDatafileKind0=PCBLib|IsCurrent=T|DatalinksLocked=T|DatabaseDatalinksLocked=T
|RECORD=46|OwnerIndex=1814
|RECORD=48|OwnerIndex=1814
|RECORD=41|OwnerIndex=1816|IndexInSheet=-1|OwnerPartId=-1|Color=8388608|FontID=1|IsHidden=T|Text=2D|Name=Available Preview Images
|RECORD=45|OwnerIndex=1813|IndexInSheet=-1|Description=Chip Resistor, 2-Leads, Body 1.00x0.50mm, IPC High Density|UseComponentLibrary=T|ModelName=RESC1005X40X25LL05T05|ModelType=PCBLIB|DatafileCount=1|ModelDatafileEntity0=RESC1005X40X25LL05T05|ModelDatafileKind0=PCBLib|DatalinksLocked=T|DatabaseDatalinksLocked=T
|RECORD=46|OwnerIndex=1818
|RECORD=48|OwnerIndex=1818
|RECORD=41|OwnerIndex=1820|IndexInSheet=-1|OwnerPartId=-1|Color=8388608|FontID=1|IsHidden=T|Text=2D|Name=Available Preview Images
|RECORD=45|OwnerIndex=1813|IndexInSheet=-1|Description=Chip Resistor, 2-Leads, Body 1.00x0.50mm, IPC Low Density|UseComponentLibrary=T|ModelName=RESC1005X40X25ML05T05|ModelType=PCBLIB|DatafileCount=1|ModelDatafileEntity0=RESC1005X40X25ML05T05|ModelDatafileKind0=PCBLib|DatalinksLocked=T|DatabaseDatalinksLocked=T
|RECORD=46|OwnerIndex=1822
|RECORD=48|OwnerIndex=1822
|RECORD=41|OwnerIndex=1824|IndexInSheet=-1|OwnerPartId=-1|Color=8388608|FontID=1|IsHidden=T|Text=2D|Name=Available Preview Images
|RECORD=1|LibReference=RES|PartCount=2|DisplayModeCount=2|IndexInSheet=245|OwnerPartId=-1|Location.X=780|Location.Y=550|CurrentPartId=1|SourceLibraryName=Altium Content Vault|TargetFileName=*|AreaColor=11599871|Color=128|PartIDLocked=F|DesignItemId=CMP-2002-08434-1|AllPinCount=2|ComponentKindVersion2=5
|RECORD=2|OwnerIndex=1826|OwnerPartId=1|OwnerPartDisplayMode=1|FormalType=1|Electrical=4|PinConglomerate=32|PinLength=10|Location.X=800|Location.Y=540|Name=2|Designator=2|PinPropagationDelay=0.000000E+000
|RECORD=2|OwnerIndex=1826|OwnerPartId=1|OwnerPartDisplayMode=1|FormalType=1|Electrical=4|PinConglomerate=34|PinLength=10|Location.X=780|Location.Y=540|Name=1|Designator=1|PinPropagationDelay=0.000000E+000
|RECORD=14|OwnerIndex=1826|IsNotAccesible=T|IndexInSheet=2|OwnerPartId=1|OwnerPartDisplayMode=1|Location.X=780|Location.Y=536|Corner.X=800|Corner.Y=544|LineWidth=1|Color=16711680|AreaColor=11599871
|RECORD=2|OwnerIndex=1826|OwnerPartId=1|FormalType=1|Electrical=4|PinConglomerate=32|PinLength=10|Location.X=800|Location.Y=540|Name=2|Designator=2|PinPropagationDelay=0.000000E+000
|RECORD=2|OwnerIndex=1826|OwnerPartId=1|FormalType=1|Electrical=4|PinConglomerate=34|PinLength=10|Location.X=780|Location.Y=540|Name=1|Designator=1|PinPropagationDelay=0.000000E+000
|RECORD=6|OwnerIndex=1826|IsNotAccesible=T|IndexInSheet=5|OwnerPartId=1|LineWidth=1|Color=16711680|LocationCount=10|X1=800|Y1=540|X2=796|Y2=540|X3=795|Y3=538|X4=793|Y4=542|X5=791|Y5=538|X6=789|Y6=542|X7=787|Y7=538|X8=785|Y8=542|X9=784|Y9=540|X10=780|Y10=540
|RECORD=41|OwnerIndex=1826|IndexInSheet=6|OwnerPartId=-1|Location.X=768|Location.Y=553|Color=8388608|FontID=1|IsHidden=T|Text=CRCW040227R0FKED|Name=Part Number
|RECORD=41|OwnerIndex=1826|IndexInSheet=7|OwnerPartId=-1|Location.X=768|Location.Y=553|Color=8388608|FontID=1|IsHidden=T|Text=Vishay Dale|Name=Manufacturer
|RECORD=34|OwnerIndex=1826|IndexInSheet=-1|OwnerPartId=-1|Location.X=760|Location.Y=540|Color=8388608|FontID=1|Text=R103|Name=Designator|ReadOnlyState=1
|RECORD=41|OwnerIndex=1826|IndexInSheet=-1|OwnerPartId=-1|Location.X=780|Location.Y=540|Color=8388608|FontID=1|Text=DNI_27_1%_0402|Name=Comment
|RECORD=44|OwnerIndex=1826
|RECORD=45|OwnerIndex=1841|IndexInSheet=-1|Description=Chip Resistor, 2-Leads, Body 1.00x0.50mm, IPC Medium Density|UseComponentLibrary=T|ModelName=RESC1005X40X25NL05T05|ModelType=PCBLIB|DatafileCount=1|ModelDatafileEntity0=RESC1005X40X25NL05T05|ModelDatafileKind0=PCBLib|IsCurrent=T|DatalinksLocked=T|DatabaseDatalinksLocked=T
|RECORD=46|OwnerIndex=1842
|RECORD=48|OwnerIndex=1842
|RECORD=41|OwnerIndex=1844|IndexInSheet=-1|OwnerPartId=-1|Color=8388608|FontID=1|IsHidden=T|Text=2D|Name=Available Preview Images
|RECORD=45|OwnerIndex=1841|IndexInSheet=-1|Description=Chip Resistor, 2-Leads, Body 1.00x0.50mm, IPC High Density|UseComponentLibrary=T|ModelName=RESC1005X40X25LL05T05|ModelType=PCBLIB|DatafileCount=1|ModelDatafileEntity0=RESC1005X40X25LL05T05|ModelDatafileKind0=PCBLib|DatalinksLocked=T|DatabaseDatalinksLocked=T
|RECORD=46|OwnerIndex=1846
|RECORD=48|OwnerIndex=1846
|RECORD=41|OwnerIndex=1848|IndexInSheet=-1|OwnerPartId=-1|Color=8388608|FontID=1|IsHidden=T|Text=2D|Name=Available Preview Images
|RECORD=45|OwnerIndex=1841|IndexInSheet=-1|Description=Chip Resistor, 2-Leads, Body 1.00x0.50mm, IPC Low Density|UseComponentLibrary=T|ModelName=RESC1005X40X25ML05T05|ModelType=PCBLIB|DatafileCount=1|ModelDatafileEntity0=RESC1005X40X25ML05T05|ModelDatafileKind0=PCBLib|DatalinksLocked=T|DatabaseDatalinksLocked=T
|RECORD=46|OwnerIndex=1850
|RECORD=48|OwnerIndex=1850
|RECORD=41|OwnerIndex=1852|IndexInSheet=-1|OwnerPartId=-1|Color=8388608|FontID=1|IsHidden=T|Text=2D|Name=Available Preview Images
|RECORD=27|IndexInSheet=246|OwnerPartId=-1|LineWidth=1|Color=8388608|LocationCount=3|X1=810|Y1=540|X2=860|Y2=540|X3=860|Y3=440
|RECORD=27|IndexInSheet=247|OwnerPartId=-1|LineWidth=1|Color=8388608|LocationCount=3|X1=810|Y1=570|X2=840|Y2=570|X3=840|Y3=480
|RECORD=17|IndexInSheet=248|OwnerPartId=-1|ShowNetName=T|Location.X=750|Location.Y=540|Orientation=2|Color=255|FontID=1|Text=GPS2_RX_FPGA|IsCrossSheetConnector=T
|RECORD=17|IndexInSheet=249|OwnerPartId=-1|ShowNetName=T|Location.X=750|Location.Y=570|Orientation=2|Color=255|FontID=1|Text=GPS2_TX_FPGA|IsCrossSheetConnector=T
|RECORD=27|IndexInSheet=250|OwnerPartId=-1|LineWidth=1|Color=8388608|LocationCount=2|X1=750|Y1=570|X2=770|Y2=570
|RECORD=27|IndexInSheet=251|OwnerPartId=-1|LineWidth=1|Color=8388608|LocationCount=2|X1=750|Y1=540|X2=770|Y2=540
|RECORD=1|LibReference=RES|PartCount=2|DisplayModeCount=2|IndexInSheet=252|OwnerPartId=-1|Location.X=1290|Location.Y=740|CurrentPartId=1|SourceLibraryName=Altium Content Vault|TargetFileName=*|AreaColor=11599871|Color=128|PartIDLocked=F|DesignItemId=CMP-2002-08434-1|AllPinCount=2|ComponentKindVersion2=5
|RECORD=2|OwnerIndex=1860|OwnerPartId=1|OwnerPartDisplayMode=1|FormalType=1|Electrical=4|PinConglomerate=32|PinLength=10|Location.X=1310|Location.Y=730|Name=2|Designator=2|PinPropagationDelay=0.000000E+000
|RECORD=2|OwnerIndex=1860|OwnerPartId=1|OwnerPartDisplayMode=1|FormalType=1|Electrical=4|PinConglomerate=34|PinLength=10|Location.X=1290|Location.Y=730|Name=1|Designator=1|PinPropagationDelay=0.000000E+000
|RECORD=14|OwnerIndex=1860|IsNotAccesible=T|IndexInSheet=2|OwnerPartId=1|OwnerPartDisplayMode=1|Location.X=1290|Location.Y=726|Corner.X=1310|Corner.Y=734|LineWidth=1|Color=16711680|AreaColor=11599871
|RECORD=2|OwnerIndex=1860|OwnerPartId=1|FormalType=1|Electrical=4|PinConglomerate=32|PinLength=10|Location.X=1310|Location.Y=730|Name=2|Designator=2|PinPropagationDelay=0.000000E+000
|RECORD=2|OwnerIndex=1860|OwnerPartId=1|FormalType=1|Electrical=4|PinConglomerate=34|PinLength=10|Location.X=1290|Location.Y=730|Name=1|Designator=1|PinPropagationDelay=0.000000E+000
|RECORD=6|OwnerIndex=1860|IsNotAccesible=T|IndexInSheet=5|OwnerPartId=1|LineWidth=1|Color=16711680|LocationCount=10|X1=1310|Y1=730|X2=1306|Y2=730|X3=1305|Y3=728|X4=1303|Y4=732|X5=1301|Y5=728|X6=1299|Y6=732|X7=1297|Y7=728|X8=1295|Y8=732|X9=1294|Y9=730|X10=1290|Y10=730
|RECORD=41|OwnerIndex=1860|IndexInSheet=6|OwnerPartId=-1|Location.X=1278|Location.Y=743|Color=8388608|FontID=1|IsHidden=T|Text=CRCW040227R0FKED|Name=Part Number
|RECORD=41|OwnerIndex=1860|IndexInSheet=7|OwnerPartId=-1|Location.X=1278|Location.Y=743|Color=8388608|FontID=1|IsHidden=T|Text=Vishay Dale|Name=Manufacturer
|RECORD=34|OwnerIndex=1860|IndexInSheet=-1|OwnerPartId=-1|Location.X=1270|Location.Y=730|Color=8388608|FontID=1|Text=R100|Name=Designator|ReadOnlyState=1
|RECORD=41|OwnerIndex=1860|IndexInSheet=-1|OwnerPartId=-1|Location.X=1290|Location.Y=730|Color=8388608|FontID=1|Text=DNI_27_1%_0402|Name=Comment
|RECORD=44|OwnerIndex=1860
|RECORD=45|OwnerIndex=1875|IndexInSheet=-1|Description=Chip Resistor, 2-Leads, Body 1.00x0.50mm, IPC Medium Density|UseComponentLibrary=T|ModelName=RESC1005X40X25NL05T05|ModelType=PCBLIB|DatafileCount=1|ModelDatafileEntity0=RESC1005X40X25NL05T05|ModelDatafileKind0=PCBLib|IsCurrent=T|DatalinksLocked=T|DatabaseDatalinksLocked=T
|RECORD=46|OwnerIndex=1876
|RECORD=48|OwnerIndex=1876
|RECORD=41|OwnerIndex=1878|IndexInSheet=-1|OwnerPartId=-1|Color=8388608|FontID=1|IsHidden=T|Text=2D|Name=Available Preview Images
|RECORD=45|OwnerIndex=1875|IndexInSheet=-1|Description=Chip Resistor, 2-Leads, Body 1.00x0.50mm, IPC High Density|UseComponentLibrary=T|ModelName=RESC1005X40X25LL05T05|ModelType=PCBLIB|DatafileCount=1|ModelDatafileEntity0=RESC1005X40X25LL05T05|ModelDatafileKind0=PCBLib|DatalinksLocked=T|DatabaseDatalinksLocked=T
|RECORD=46|OwnerIndex=1880
|RECORD=48|OwnerIndex=1880
|RECORD=41|OwnerIndex=1882|IndexInSheet=-1|OwnerPartId=-1|Color=8388608|FontID=1|IsHidden=T|Text=2D|Name=Available Preview Images
|RECORD=45|OwnerIndex=1875|IndexInSheet=-1|Description=Chip Resistor, 2-Leads, Body 1.00x0.50mm, IPC Low Density|UseComponentLibrary=T|ModelName=RESC1005X40X25ML05T05|ModelType=PCBLIB|DatafileCount=1|ModelDatafileEntity0=RESC1005X40X25ML05T05|ModelDatafileKind0=PCBLib|DatalinksLocked=T|DatabaseDatalinksLocked=T
|RECORD=46|OwnerIndex=1884
|RECORD=48|OwnerIndex=1884
|RECORD=41|OwnerIndex=1886|IndexInSheet=-1|OwnerPartId=-1|Color=8388608|FontID=1|IsHidden=T|Text=2D|Name=Available Preview Images
|RECORD=1|LibReference=RES|PartCount=2|DisplayModeCount=2|IndexInSheet=253|OwnerPartId=-1|Location.X=1290|Location.Y=720|CurrentPartId=1|SourceLibraryName=Altium Content Vault|TargetFileName=*|AreaColor=11599871|Color=128|PartIDLocked=F|DesignItemId=CMP-2002-08434-1|AllPinCount=2|ComponentKindVersion2=5
|RECORD=2|OwnerIndex=1888|OwnerPartId=1|OwnerPartDisplayMode=1|FormalType=1|Electrical=4|PinConglomerate=32|PinLength=10|Location.X=1310|Location.Y=710|Name=2|Designator=2|PinPropagationDelay=0.000000E+000
|RECORD=2|OwnerIndex=1888|OwnerPartId=1|OwnerPartDisplayMode=1|FormalType=1|Electrical=4|PinConglomerate=34|PinLength=10|Location.X=1290|Location.Y=710|Name=1|Designator=1|PinPropagationDelay=0.000000E+000
|RECORD=14|OwnerIndex=1888|IsNotAccesible=T|IndexInSheet=2|OwnerPartId=1|OwnerPartDisplayMode=1|Location.X=1290|Location.Y=706|Corner.X=1310|Corner.Y=714|LineWidth=1|Color=16711680|AreaColor=11599871
|RECORD=2|OwnerIndex=1888|OwnerPartId=1|FormalType=1|Electrical=4|PinConglomerate=32|PinLength=10|Location.X=1310|Location.Y=710|Name=2|Designator=2|PinPropagationDelay=0.000000E+000
|RECORD=2|OwnerIndex=1888|OwnerPartId=1|FormalType=1|Electrical=4|PinConglomerate=34|PinLength=10|Location.X=1290|Location.Y=710|Name=1|Designator=1|PinPropagationDelay=0.000000E+000
|RECORD=6|OwnerIndex=1888|IsNotAccesible=T|IndexInSheet=5|OwnerPartId=1|LineWidth=1|Color=16711680|LocationCount=10|X1=1310|Y1=710|X2=1306|Y2=710|X3=1305|Y3=708|X4=1303|Y4=712|X5=1301|Y5=708|X6=1299|Y6=712|X7=1297|Y7=708|X8=1295|Y8=712|X9=1294|Y9=710|X10=1290|Y10=710
|RECORD=41|OwnerIndex=1888|IndexInSheet=6|OwnerPartId=-1|Location.X=1278|Location.Y=723|Color=8388608|FontID=1|IsHidden=T|Text=CRCW040227R0FKED|Name=Part Number
|RECORD=41|OwnerIndex=1888|IndexInSheet=7|OwnerPartId=-1|Location.X=1278|Location.Y=723|Color=8388608|FontID=1|IsHidden=T|Text=Vishay Dale|Name=Manufacturer
|RECORD=34|OwnerIndex=1888|IndexInSheet=-1|OwnerPartId=-1|Location.X=1270|Location.Y=710|Color=8388608|FontID=1|Text=R101|Name=Designator|ReadOnlyState=1
|RECORD=41|OwnerIndex=1888|IndexInSheet=-1|OwnerPartId=-1|Location.X=1290|Location.Y=710|Color=8388608|FontID=1|Text=DNI_27_1%_0402|Name=Comment
|RECORD=44|OwnerIndex=1888
|RECORD=45|OwnerIndex=1903|IndexInSheet=-1|Description=Chip Resistor, 2-Leads, Body 1.00x0.50mm, IPC Medium Density|UseComponentLibrary=T|ModelName=RESC1005X40X25NL05T05|ModelType=PCBLIB|DatafileCount=1|ModelDatafileEntity0=RESC1005X40X25NL05T05|ModelDatafileKind0=PCBLib|IsCurrent=T|DatalinksLocked=T|DatabaseDatalinksLocked=T
|RECORD=46|OwnerIndex=1904
|RECORD=48|OwnerIndex=1904
|RECORD=41|OwnerIndex=1906|IndexInSheet=-1|OwnerPartId=-1|Color=8388608|FontID=1|IsHidden=T|Text=2D|Name=Available Preview Images
|RECORD=45|OwnerIndex=1903|IndexInSheet=-1|Description=Chip Resistor, 2-Leads, Body 1.00x0.50mm, IPC High Density|UseComponentLibrary=T|ModelName=RESC1005X40X25LL05T05|ModelType=PCBLIB|DatafileCount=1|ModelDatafileEntity0=RESC1005X40X25LL05T05|ModelDatafileKind0=PCBLib|DatalinksLocked=T|DatabaseDatalinksLocked=T
|RECORD=46|OwnerIndex=1908
|RECORD=48|OwnerIndex=1908
|RECORD=41|OwnerIndex=1910|IndexInSheet=-1|OwnerPartId=-1|Color=8388608|FontID=1|IsHidden=T|Text=2D|Name=Available Preview Images
|RECORD=45|OwnerIndex=1903|IndexInSheet=-1|Description=Chip Resistor, 2-Leads, Body 1.00x0.50mm, IPC Low Density|UseComponentLibrary=T|ModelName=RESC1005X40X25ML05T05|ModelType=PCBLIB|DatafileCount=1|ModelDatafileEntity0=RESC1005X40X25ML05T05|ModelDatafileKind0=PCBLib|DatalinksLocked=T|DatabaseDatalinksLocked=T
|RECORD=46|OwnerIndex=1912
|RECORD=48|OwnerIndex=1912
|RECORD=41|OwnerIndex=1914|IndexInSheet=-1|OwnerPartId=-1|Color=8388608|FontID=1|IsHidden=T|Text=2D|Name=Available Preview Images
|RECORD=17|IndexInSheet=254|OwnerPartId=-1|Style=1|ShowNetName=T|Location.X=1250|Location.Y=730|Orientation=2|Color=255|FontID=1|Text=FTDI_RX|IsCrossSheetConnector=T
|RECORD=27|IndexInSheet=255|OwnerPartId=-1|LineWidth=1|Color=8388608|LocationCount=3|X1=1320|Y1=730|X2=1360|Y2=730|X3=1360|Y3=600
|RECORD=27|IndexInSheet=256|OwnerPartId=-1|LineWidth=1|Color=8388608|LocationCount=3|X1=1320|Y1=710|X2=1370|Y2=710|X3=1370|Y3=560
|RECORD=17|IndexInSheet=257|OwnerPartId=-1|ShowNetName=T|Location.X=1250|Location.Y=710|Orientation=2|Color=255|FontID=1|Text=FTDI_TX|IsCrossSheetConnector=T
|RECORD=27|IndexInSheet=258|OwnerPartId=-1|LineWidth=1|Color=8388608|LocationCount=2|X1=1280|Y1=710|X2=1250|Y2=710
|RECORD=27|IndexInSheet=259|OwnerPartId=-1|LineWidth=1|Color=8388608|LocationCount=2|X1=1280|Y1=730|X2=1250|Y2=730
|RECORD=1|LibReference=RES|PartCount=2|DisplayModeCount=2|IndexInSheet=260|OwnerPartId=-1|Location.X=710|Location.Y=260|CurrentPartId=1|SourceLibraryName=Altium Content Vault|TargetFileName=*|AreaColor=11599871|Color=128|PartIDLocked=F|DesignItemId=CMP-2002-07709-1|AllPinCount=2|ComponentKindVersion2=5
|RECORD=2|OwnerIndex=1922|OwnerPartId=1|OwnerPartDisplayMode=1|FormalType=1|Electrical=4|PinConglomerate=32|PinLength=10|Location.X=730|Location.Y=250|Name=2|Designator=2|PinPropagationDelay=0.000000E+000
|RECORD=2|OwnerIndex=1922|OwnerPartId=1|OwnerPartDisplayMode=1|FormalType=1|Electrical=4|PinConglomerate=34|PinLength=10|Location.X=710|Location.Y=250|Name=1|Designator=1|PinPropagationDelay=0.000000E+000
|RECORD=14|OwnerIndex=1922|IsNotAccesible=T|IndexInSheet=2|OwnerPartId=1|OwnerPartDisplayMode=1|Location.X=710|Location.Y=246|Corner.X=730|Corner.Y=254|LineWidth=1|Color=16711680|AreaColor=11599871
|RECORD=2|OwnerIndex=1922|OwnerPartId=1|FormalType=1|Electrical=4|PinConglomerate=32|PinLength=10|Location.X=730|Location.Y=250|Name=2|Designator=2|PinPropagationDelay=0.000000E+000
|RECORD=2|OwnerIndex=1922|OwnerPartId=1|FormalType=1|Electrical=4|PinConglomerate=34|PinLength=10|Location.X=710|Location.Y=250|Name=1|Designator=1|PinPropagationDelay=0.000000E+000
|RECORD=6|OwnerIndex=1922|IsNotAccesible=T|IndexInSheet=5|OwnerPartId=1|LineWidth=1|Color=16711680|LocationCount=10|X1=730|Y1=250|X2=726|Y2=250|X3=725|Y3=248|X4=723|Y4=252|X5=721|Y5=248|X6=719|Y6=252|X7=717|Y7=248|X8=715|Y8=252|X9=714|Y9=250|X10=710|Y10=250
|RECORD=41|OwnerIndex=1922|IndexInSheet=6|OwnerPartId=-1|Location.X=698|Location.Y=263|Color=8388608|FontID=1|IsHidden=T|Text=Yageo / Phycomp|Name=Manufacturer
|RECORD=41|OwnerIndex=1922|IndexInSheet=7|OwnerPartId=-1|Location.X=698|Location.Y=263|Color=8388608|FontID=1|IsHidden=T|Text=RC0402FR-0749R9L|Name=Part Number
|RECORD=34|OwnerIndex=1922|IndexInSheet=-1|OwnerPartId=-1|Location.X=690|Location.Y=250|Color=8388608|FontID=1|Text=R107|Name=Designator|ReadOnlyState=1
|RECORD=41|OwnerIndex=1922|IndexInSheet=-1|OwnerPartId=-1|Location.X=730|Location.Y=250|Color=8388608|FontID=1|Text=DNI_49.9_1%_0402|Name=Comment
|RECORD=44|OwnerIndex=1922
|RECORD=45|OwnerIndex=1937|IndexInSheet=-1|Description=Chip Resistor, 2-Leads, Body 1.00x0.50mm, IPC High Density|UseComponentLibrary=T|ModelName=RESC1005X40X25LL05T10|ModelType=PCBLIB|DatafileCount=1|ModelDatafileEntity0=RESC1005X40X25LL05T10|ModelDatafileKind0=PCBLib|IsCurrent=T|DatalinksLocked=T|DatabaseDatalinksLocked=T
|RECORD=46|OwnerIndex=1938
|RECORD=48|OwnerIndex=1938
|RECORD=41|OwnerIndex=1940|IndexInSheet=-1|OwnerPartId=-1|Color=8388608|FontID=1|IsHidden=T|Text=2D|Name=Available Preview Images
|RECORD=45|OwnerIndex=1937|IndexInSheet=-1|Description=Chip Resistor, 2-Leads, Body 1.00x0.50mm, IPC Low Density|UseComponentLibrary=T|ModelName=RESC1005X40X25ML05T10|ModelType=PCBLIB|DatafileCount=1|ModelDatafileEntity0=RESC1005X40X25ML05T10|ModelDatafileKind0=PCBLib|DatalinksLocked=T|DatabaseDatalinksLocked=T
|RECORD=46|OwnerIndex=1942
|RECORD=48|OwnerIndex=1942
|RECORD=41|OwnerIndex=1944|IndexInSheet=-1|OwnerPartId=-1|Color=8388608|FontID=1|IsHidden=T|Text=2D|Name=Available Preview Images
|RECORD=45|OwnerIndex=1937|IndexInSheet=-1|Description=Chip Resistor, 2-Leads, Body 1.00x0.50mm, IPC Medium Density|UseComponentLibrary=T|ModelName=RESC1005X40X25NL05T10|ModelType=PCBLIB|DatafileCount=1|ModelDatafileEntity0=RESC1005X40X25NL05T10|ModelDatafileKind0=PCBLib|DatalinksLocked=T|DatabaseDatalinksLocked=T
|RECORD=46|OwnerIndex=1946
|RECORD=48|OwnerIndex=1946
|RECORD=41|OwnerIndex=1948|IndexInSheet=-1|OwnerPartId=-1|Color=8388608|FontID=1|IsHidden=T|Text=2D|Name=Available Preview Images
|RECORD=1|LibReference=RES|PartCount=2|DisplayModeCount=2|IndexInSheet=261|OwnerPartId=-1|Location.X=710|Location.Y=280|CurrentPartId=1|SourceLibraryName=Altium Content Vault|TargetFileName=*|AreaColor=11599871|Color=128|PartIDLocked=F|DesignItemId=CMP-2002-07709-1|AllPinCount=2|ComponentKindVersion2=5
|RECORD=2|OwnerIndex=1950|OwnerPartId=1|OwnerPartDisplayMode=1|FormalType=1|Electrical=4|PinConglomerate=32|PinLength=10|Location.X=730|Location.Y=270|Name=2|Designator=2|PinPropagationDelay=0.000000E+000
|RECORD=2|OwnerIndex=1950|OwnerPartId=1|OwnerPartDisplayMode=1|FormalType=1|Electrical=4|PinConglomerate=34|PinLength=10|Location.X=710|Location.Y=270|Name=1|Designator=1|PinPropagationDelay=0.000000E+000
|RECORD=14|OwnerIndex=1950|IsNotAccesible=T|IndexInSheet=2|OwnerPartId=1|OwnerPartDisplayMode=1|Location.X=710|Location.Y=266|Corner.X=730|Corner.Y=274|LineWidth=1|Color=16711680|AreaColor=11599871
|RECORD=2|OwnerIndex=1950|OwnerPartId=1|FormalType=1|Electrical=4|PinConglomerate=32|PinLength=10|Location.X=730|Location.Y=270|Name=2|Designator=2|PinPropagationDelay=0.000000E+000
|RECORD=2|OwnerIndex=1950|OwnerPartId=1|FormalType=1|Electrical=4|PinConglomerate=34|PinLength=10|Location.X=710|Location.Y=270|Name=1|Designator=1|PinPropagationDelay=0.000000E+000
|RECORD=6|OwnerIndex=1950|IsNotAccesible=T|IndexInSheet=5|OwnerPartId=1|LineWidth=1|Color=16711680|LocationCount=10|X1=730|Y1=270|X2=726|Y2=270|X3=725|Y3=268|X4=723|Y4=272|X5=721|Y5=268|X6=719|Y6=272|X7=717|Y7=268|X8=715|Y8=272|X9=714|Y9=270|X10=710|Y10=270
|RECORD=41|OwnerIndex=1950|IndexInSheet=6|OwnerPartId=-1|Location.X=698|Location.Y=283|Color=8388608|FontID=1|IsHidden=T|Text=Yageo / Phycomp|Name=Manufacturer
|RECORD=41|OwnerIndex=1950|IndexInSheet=7|OwnerPartId=-1|Location.X=698|Location.Y=283|Color=8388608|FontID=1|IsHidden=T|Text=RC0402FR-0749R9L|Name=Part Number
|RECORD=34|OwnerIndex=1950|IndexInSheet=-1|OwnerPartId=-1|Location.X=690|Location.Y=270|Color=8388608|FontID=1|Text=R105|Name=Designator|ReadOnlyState=1
|RECORD=41|OwnerIndex=1950|IndexInSheet=-1|OwnerPartId=-1|Location.X=730|Location.Y=270|Color=8388608|FontID=1|Text=DNI_49.9_1%_0402|Name=Comment
|RECORD=44|OwnerIndex=1950
|RECORD=45|OwnerIndex=1965|IndexInSheet=-1|Description=Chip Resistor, 2-Leads, Body 1.00x0.50mm, IPC High Density|UseComponentLibrary=T|ModelName=RESC1005X40X25LL05T10|ModelType=PCBLIB|DatafileCount=1|ModelDatafileEntity0=RESC1005X40X25LL05T10|ModelDatafileKind0=PCBLib|IsCurrent=T|DatalinksLocked=T|DatabaseDatalinksLocked=T
|RECORD=46|OwnerIndex=1966
|RECORD=48|OwnerIndex=1966
|RECORD=41|OwnerIndex=1968|IndexInSheet=-1|OwnerPartId=-1|Color=8388608|FontID=1|IsHidden=T|Text=2D|Name=Available Preview Images
|RECORD=45|OwnerIndex=1965|IndexInSheet=-1|Description=Chip Resistor, 2-Leads, Body 1.00x0.50mm, IPC Low Density|UseComponentLibrary=T|ModelName=RESC1005X40X25ML05T10|ModelType=PCBLIB|DatafileCount=1|ModelDatafileEntity0=RESC1005X40X25ML05T10|ModelDatafileKind0=PCBLib|DatalinksLocked=T|DatabaseDatalinksLocked=T
|RECORD=46|OwnerIndex=1970
|RECORD=48|OwnerIndex=1970
|RECORD=41|OwnerIndex=1972|IndexInSheet=-1|OwnerPartId=-1|Color=8388608|FontID=1|IsHidden=T|Text=2D|Name=Available Preview Images
|RECORD=45|OwnerIndex=1965|IndexInSheet=-1|Description=Chip Resistor, 2-Leads, Body 1.00x0.50mm, IPC Medium Density|UseComponentLibrary=T|ModelName=RESC1005X40X25NL05T10|ModelType=PCBLIB|DatafileCount=1|ModelDatafileEntity0=RESC1005X40X25NL05T10|ModelDatafileKind0=PCBLib|DatalinksLocked=T|DatabaseDatalinksLocked=T
|RECORD=46|OwnerIndex=1974
|RECORD=48|OwnerIndex=1974
|RECORD=41|OwnerIndex=1976|IndexInSheet=-1|OwnerPartId=-1|Color=8388608|FontID=1|IsHidden=T|Text=2D|Name=Available Preview Images
|RECORD=1|LibReference=RES|PartCount=2|DisplayModeCount=2|IndexInSheet=262|OwnerPartId=-1|Location.X=710|Location.Y=290|CurrentPartId=1|SourceLibraryName=Altium Content Vault|TargetFileName=*|AreaColor=11599871|Color=128|PartIDLocked=F|DesignItemId=CMP-2002-07709-1|AllPinCount=2|ComponentKindVersion2=5
|RECORD=2|OwnerIndex=1978|OwnerPartId=1|OwnerPartDisplayMode=1|FormalType=1|Electrical=4|PinConglomerate=32|PinLength=10|Location.X=730|Location.Y=280|Name=2|Designator=2|PinPropagationDelay=0.000000E+000
|RECORD=2|OwnerIndex=1978|OwnerPartId=1|OwnerPartDisplayMode=1|FormalType=1|Electrical=4|PinConglomerate=34|PinLength=10|Location.X=710|Location.Y=280|Name=1|Designator=1|PinPropagationDelay=0.000000E+000
|RECORD=14|OwnerIndex=1978|IsNotAccesible=T|IndexInSheet=2|OwnerPartId=1|OwnerPartDisplayMode=1|Location.X=710|Location.Y=276|Corner.X=730|Corner.Y=284|LineWidth=1|Color=16711680|AreaColor=11599871
|RECORD=2|OwnerIndex=1978|OwnerPartId=1|FormalType=1|Electrical=4|PinConglomerate=32|PinLength=10|Location.X=730|Location.Y=280|Name=2|Designator=2|PinPropagationDelay=0.000000E+000
|RECORD=2|OwnerIndex=1978|OwnerPartId=1|FormalType=1|Electrical=4|PinConglomerate=34|PinLength=10|Location.X=710|Location.Y=280|Name=1|Designator=1|PinPropagationDelay=0.000000E+000
|RECORD=6|OwnerIndex=1978|IsNotAccesible=T|IndexInSheet=5|OwnerPartId=1|LineWidth=1|Color=16711680|LocationCount=10|X1=730|Y1=280|X2=726|Y2=280|X3=725|Y3=278|X4=723|Y4=282|X5=721|Y5=278|X6=719|Y6=282|X7=717|Y7=278|X8=715|Y8=282|X9=714|Y9=280|X10=710|Y10=280
|RECORD=41|OwnerIndex=1978|IndexInSheet=6|OwnerPartId=-1|Location.X=698|Location.Y=293|Color=8388608|FontID=1|IsHidden=T|Text=Yageo / Phycomp|Name=Manufacturer
|RECORD=41|OwnerIndex=1978|IndexInSheet=7|OwnerPartId=-1|Location.X=698|Location.Y=293|Color=8388608|FontID=1|IsHidden=T|Text=RC0402FR-0749R9L|Name=Part Number
|RECORD=34|OwnerIndex=1978|IndexInSheet=-1|OwnerPartId=-1|Location.X=690|Location.Y=280|Color=8388608|FontID=1|Text=R104|Name=Designator|ReadOnlyState=1
|RECORD=41|OwnerIndex=1978|IndexInSheet=-1|OwnerPartId=-1|Location.X=730|Location.Y=280|Color=8388608|FontID=1|Text=DNI_49.9_1%_0402|Name=Comment
|RECORD=44|OwnerIndex=1978
|RECORD=45|OwnerIndex=1993|IndexInSheet=-1|Description=Chip Resistor, 2-Leads, Body 1.00x0.50mm, IPC High Density|UseComponentLibrary=T|ModelName=RESC1005X40X25LL05T10|ModelType=PCBLIB|DatafileCount=1|ModelDatafileEntity0=RESC1005X40X25LL05T10|ModelDatafileKind0=PCBLib|IsCurrent=T|DatalinksLocked=T|DatabaseDatalinksLocked=T
|RECORD=46|OwnerIndex=1994
|RECORD=48|OwnerIndex=1994
|RECORD=41|OwnerIndex=1996|IndexInSheet=-1|OwnerPartId=-1|Color=8388608|FontID=1|IsHidden=T|Text=2D|Name=Available Preview Images
|RECORD=45|OwnerIndex=1993|IndexInSheet=-1|Description=Chip Resistor, 2-Leads, Body 1.00x0.50mm, IPC Low Density|UseComponentLibrary=T|ModelName=RESC1005X40X25ML05T10|ModelType=PCBLIB|DatafileCount=1|ModelDatafileEntity0=RESC1005X40X25ML05T10|ModelDatafileKind0=PCBLib|DatalinksLocked=T|DatabaseDatalinksLocked=T
|RECORD=46|OwnerIndex=1998
|RECORD=48|OwnerIndex=1998
|RECORD=41|OwnerIndex=2000|IndexInSheet=-1|OwnerPartId=-1|Color=8388608|FontID=1|IsHidden=T|Text=2D|Name=Available Preview Images
|RECORD=45|OwnerIndex=1993|IndexInSheet=-1|Description=Chip Resistor, 2-Leads, Body 1.00x0.50mm, IPC Medium Density|UseComponentLibrary=T|ModelName=RESC1005X40X25NL05T10|ModelType=PCBLIB|DatafileCount=1|ModelDatafileEntity0=RESC1005X40X25NL05T10|ModelDatafileKind0=PCBLib|DatalinksLocked=T|DatabaseDatalinksLocked=T
|RECORD=46|OwnerIndex=2002
|RECORD=48|OwnerIndex=2002
|RECORD=41|OwnerIndex=2004|IndexInSheet=-1|OwnerPartId=-1|Color=8388608|FontID=1|IsHidden=T|Text=2D|Name=Available Preview Images
|RECORD=17|IndexInSheet=263|OwnerPartId=-1|ShowNetName=T|Location.X=820|Location.Y=280|Color=255|FontID=1|Text=MAC_PPS_OUT|IsCrossSheetConnector=T
|RECORD=1|LibReference=RES|PartCount=2|DisplayModeCount=2|IndexInSheet=264|OwnerPartId=-1|Location.X=710|Location.Y=270|CurrentPartId=1|SourceLibraryName=Altium Content Vault|TargetFileName=*|AreaColor=11599871|Color=128|PartIDLocked=F|DesignItemId=CMP-2002-07709-1|AllPinCount=2|ComponentKindVersion2=5
|RECORD=2|OwnerIndex=2007|OwnerPartId=1|OwnerPartDisplayMode=1|FormalType=1|Electrical=4|PinConglomerate=32|PinLength=10|Location.X=730|Location.Y=260|Name=2|Designator=2|PinPropagationDelay=0.000000E+000
|RECORD=2|OwnerIndex=2007|OwnerPartId=1|OwnerPartDisplayMode=1|FormalType=1|Electrical=4|PinConglomerate=34|PinLength=10|Location.X=710|Location.Y=260|Name=1|Designator=1|PinPropagationDelay=0.000000E+000
|RECORD=14|OwnerIndex=2007|IsNotAccesible=T|IndexInSheet=2|OwnerPartId=1|OwnerPartDisplayMode=1|Location.X=710|Location.Y=256|Corner.X=730|Corner.Y=264|LineWidth=1|Color=16711680|AreaColor=11599871
|RECORD=2|OwnerIndex=2007|OwnerPartId=1|FormalType=1|Electrical=4|PinConglomerate=32|PinLength=10|Location.X=730|Location.Y=260|Name=2|Designator=2|PinPropagationDelay=0.000000E+000
|RECORD=2|OwnerIndex=2007|OwnerPartId=1|FormalType=1|Electrical=4|PinConglomerate=34|PinLength=10|Location.X=710|Location.Y=260|Name=1|Designator=1|PinPropagationDelay=0.000000E+000
|RECORD=6|OwnerIndex=2007|IsNotAccesible=T|IndexInSheet=5|OwnerPartId=1|LineWidth=1|Color=16711680|LocationCount=10|X1=730|Y1=260|X2=726|Y2=260|X3=725|Y3=258|X4=723|Y4=262|X5=721|Y5=258|X6=719|Y6=262|X7=717|Y7=258|X8=715|Y8=262|X9=714|Y9=260|X10=710|Y10=260
|RECORD=41|OwnerIndex=2007|IndexInSheet=6|OwnerPartId=-1|Location.X=698|Location.Y=273|Color=8388608|FontID=1|IsHidden=T|Text=Yageo / Phycomp|Name=Manufacturer
|RECORD=41|OwnerIndex=2007|IndexInSheet=7|OwnerPartId=-1|Location.X=698|Location.Y=273|Color=8388608|FontID=1|IsHidden=T|Text=RC0402FR-0749R9L|Name=Part Number
|RECORD=34|OwnerIndex=2007|IndexInSheet=-1|OwnerPartId=-1|Location.X=690|Location.Y=260|Color=8388608|FontID=1|Text=R106|Name=Designator|ReadOnlyState=1
|RECORD=41|OwnerIndex=2007|IndexInSheet=-1|OwnerPartId=-1|Location.X=730|Location.Y=260|Color=8388608|FontID=1|Text=DNI_49.9_1%_0402|Name=Comment
|RECORD=44|OwnerIndex=2007
|RECORD=45|OwnerIndex=2022|IndexInSheet=-1|Description=Chip Resistor, 2-Leads, Body 1.00x0.50mm, IPC High Density|UseComponentLibrary=T|ModelName=RESC1005X40X25LL05T10|ModelType=PCBLIB|DatafileCount=1|ModelDatafileEntity0=RESC1005X40X25LL05T10|ModelDatafileKind0=PCBLib|IsCurrent=T|DatalinksLocked=T|DatabaseDatalinksLocked=T
|RECORD=46|OwnerIndex=2023
|RECORD=48|OwnerIndex=2023
|RECORD=41|OwnerIndex=2025|IndexInSheet=-1|OwnerPartId=-1|Color=8388608|FontID=1|IsHidden=T|Text=2D|Name=Available Preview Images
|RECORD=45|OwnerIndex=2022|IndexInSheet=-1|Description=Chip Resistor, 2-Leads, Body 1.00x0.50mm, IPC Low Density|UseComponentLibrary=T|ModelName=RESC1005X40X25ML05T10|ModelType=PCBLIB|DatafileCount=1|ModelDatafileEntity0=RESC1005X40X25ML05T10|ModelDatafileKind0=PCBLib|DatalinksLocked=T|DatabaseDatalinksLocked=T
|RECORD=46|OwnerIndex=2027
|RECORD=48|OwnerIndex=2027
|RECORD=41|OwnerIndex=2029|IndexInSheet=-1|OwnerPartId=-1|Color=8388608|FontID=1|IsHidden=T|Text=2D|Name=Available Preview Images
|RECORD=45|OwnerIndex=2022|IndexInSheet=-1|Description=Chip Resistor, 2-Leads, Body 1.00x0.50mm, IPC Medium Density|UseComponentLibrary=T|ModelName=RESC1005X40X25NL05T10|ModelType=PCBLIB|DatafileCount=1|ModelDatafileEntity0=RESC1005X40X25NL05T10|ModelDatafileKind0=PCBLib|DatalinksLocked=T|DatabaseDatalinksLocked=T
|RECORD=46|OwnerIndex=2031
|RECORD=48|OwnerIndex=2031
|RECORD=41|OwnerIndex=2033|IndexInSheet=-1|OwnerPartId=-1|Color=8388608|FontID=1|IsHidden=T|Text=2D|Name=Available Preview Images
|RECORD=17|IndexInSheet=265|OwnerPartId=-1|ShowNetName=T|Location.X=820|Location.Y=270|Color=255|FontID=1|Text=FPGA_MAC_PPSDIFF_OUT|IsCrossSheetConnector=T
|RECORD=17|IndexInSheet=266|OwnerPartId=-1|Style=1|ShowNetName=T|Location.X=820|Location.Y=260|Color=255|FontID=1|Text=MAC_PPS_IN|IsCrossSheetConnector=T
|RECORD=17|IndexInSheet=267|OwnerPartId=-1|Style=1|ShowNetName=T|Location.X=820|Location.Y=250|Color=255|FontID=1|Text=FPGA_MAC_PPS_DIFF_IN0|IsCrossSheetConnector=T
|RECORD=27|IndexInSheet=268|OwnerPartId=-1|LineWidth=1|Color=8388608|LocationCount=2|X1=740|Y1=250|X2=820|Y2=250
|RECORD=27|IndexInSheet=269|OwnerPartId=-1|LineWidth=1|Color=8388608|LocationCount=2|X1=820|Y1=260|X2=740|Y2=260
|RECORD=27|IndexInSheet=270|OwnerPartId=-1|LineWidth=1|Color=8388608|LocationCount=2|X1=740|Y1=270|X2=820|Y2=270
|RECORD=27|IndexInSheet=271|OwnerPartId=-1|LineWidth=1|Color=8388608|LocationCount=2|X1=820|Y1=280|X2=740|Y2=280
|RECORD=27|IndexInSheet=272|OwnerPartId=-1|LineWidth=1|Color=8388608|LocationCount=4|X1=700|Y1=280|X2=630|Y2=280|X3=630|Y3=270|X4=630|Y4=210
|RECORD=27|IndexInSheet=273|OwnerPartId=-1|LineWidth=1|Color=8388608|LocationCount=4|X1=700|Y1=260|X2=660|Y2=260|X3=660|Y3=250|X4=660|Y4=170
|RECORD=27|IndexInSheet=274|OwnerPartId=-1|LineWidth=1|Color=8388608|LocationCount=2|X1=700|Y1=270|X2=630|Y2=270
|RECORD=27|IndexInSheet=275|OwnerPartId=-1|LineWidth=1|Color=8388608|LocationCount=2|X1=700|Y1=250|X2=660|Y2=250
|RECORD=1|LibReference=1029c3af85768c4190bb7ad29bc67b5|ComponentDescription=RES SMD 15K OHM 1% 1/10W 0402|PartCount=2|DisplayModeCount=1|IndexInSheet=276|OwnerPartId=-1|Location.X=490|Location.Y=690|Orientation=1|CurrentPartId=1|LibraryPath=*|SourceLibraryName=Altium Content Vault|TargetFileName=*|AreaColor=11599871|Color=128|PartIDLocked=T|DesignItemId=CMP-2002-00694-4|AllPinCount=2
|RECORD=2|OwnerIndex=2046|OwnerPartId=1|Electrical=4|PinConglomerate=51|PinLength=20|Location.X=490|Location.Y=710|Name=1|Designator=1|PinPropagationDelay=0.000000E+000
|RECORD=2|OwnerIndex=2046|OwnerPartId=1|Electrical=4|PinConglomerate=49|PinLength=20|Location.X=490|Location.Y=740|Name=2|Designator=2|PinPropagationDelay=0.000000E+000
|RECORD=13|OwnerIndex=2046|IsNotAccesible=T|IndexInSheet=2|OwnerPartId=1|Location.X=490|Location.Y=710|Corner.X=485|Corner.Y=713|LineWidth=1|Color=16711680
|RECORD=13|OwnerIndex=2046|IsNotAccesible=T|IndexInSheet=3|OwnerPartId=1|Location.X=485|Location.Y=713|Corner.X=495|Corner.Y=718|LineWidth=1|Color=16711680
|RECORD=13|OwnerIndex=2046|IsNotAccesible=T|IndexInSheet=4|OwnerPartId=1|Location.X=495|Location.Y=718|Corner.X=485|Corner.Y=723|LineWidth=1|Color=16711680
|RECORD=13|OwnerIndex=2046|IsNotAccesible=T|IndexInSheet=5|OwnerPartId=1|Location.X=485|Location.Y=723|Corner.X=495|Corner.Y=728|LineWidth=1|Color=16711680
|RECORD=13|OwnerIndex=2046|IsNotAccesible=T|IndexInSheet=6|OwnerPartId=1|Location.X=495|Location.Y=728|Corner.X=485|Corner.Y=733|LineWidth=1|Color=16711680
|RECORD=13|OwnerIndex=2046|IsNotAccesible=T|IndexInSheet=7|OwnerPartId=1|Location.X=485|Location.Y=733|Corner.X=495|Corner.Y=738|LineWidth=1|Color=16711680
|RECORD=13|OwnerIndex=2046|IsNotAccesible=T|IndexInSheet=8|OwnerPartId=1|Location.X=495|Location.Y=738|Corner.X=490|Corner.Y=740|LineWidth=1|Color=16711680
|RECORD=13|OwnerIndex=2046|IsNotAccesible=T|IndexInSheet=9|OwnerPartId=1|Location.X=490|Location.Y=710|Corner.X=490|Corner.Y=707|LineWidth=1|Color=16711680
|RECORD=13|OwnerIndex=2046|IsNotAccesible=T|IndexInSheet=10|OwnerPartId=1|Location.X=490|Location.Y=740|Corner.X=490|Corner.Y=743|LineWidth=1|Color=16711680
|RECORD=41|OwnerIndex=2046|IndexInSheet=11|OwnerPartId=-1|Location.X=484|Location.Y=762|Color=8388608|FontID=3|IsHidden=T|Text=https://industrial.panasonic.com/cdbs/www-data/pdf/RDA0000/AOA0000C304.pdf|Name=ComponentLink2URL
|RECORD=41|OwnerIndex=2046|IndexInSheet=12|OwnerPartId=-1|Location.X=484|Location.Y=762|Color=8388608|FontID=1|IsHidden=T|Text=Yes|Name=Automotive
|RECORD=41|OwnerIndex=2046|IndexInSheet=13|OwnerPartId=-1|Location.X=484|Location.Y=762|Color=8388608|FontID=1|IsHidden=T|Text=-55°C to +155°C|Name=Temperature
|RECORD=41|OwnerIndex=2046|IndexInSheet=14|OwnerPartId=-1|Location.X=484|Location.Y=762|Color=8388608|FontID=1|IsHidden=T|Text=0.4mm|Name=Height
|RECORD=41|OwnerIndex=2046|IndexInSheet=15|OwnerPartId=-1|Location.X=484|Location.Y=762|Color=8388608|FontID=1|IsHidden=T|Text=Grade 0|Name=Automotive Grade
|RECORD=41|OwnerIndex=2046|IndexInSheet=16|OwnerPartId=-1|Location.X=484|Location.Y=762|Color=8388608|FontID=1|IsHidden=T|Text=RES SMD 15K OHM 1% 1/10W 0402|Name=Digikey Description
|RECORD=41|OwnerIndex=2046|IndexInSheet=17|OwnerPartId=-1|Location.X=484|Location.Y=762|Color=8388608|FontID=1|IsHidden=T|Text=50V|Name=Voltage Rating
|RECORD=41|OwnerIndex=2046|IndexInSheet=18|OwnerPartId=-1|Location.X=484|Location.Y=762|Color=8388608|FontID=1|IsHidden=T|Text=Res|Name=Category
|RECORD=41|OwnerIndex=2046|IndexInSheet=19|OwnerPartId=-1|Location.X=484|Location.Y=762|Color=8388608|FontID=1|IsHidden=T|Text=Resistors|Name=Device Class L2
|RECORD=41|OwnerIndex=2046|IndexInSheet=20|OwnerPartId=-1|Location.X=484|Location.Y=762|Color=8388608|FontID=1|IsHidden=T|Text=Passive Components|Name=Device Class L1
|RECORD=41|OwnerIndex=2046|IndexInSheet=21|OwnerPartId=-1|Location.X=484|Location.Y=762|Color=8388608|FontID=1|IsHidden=T|Text=ERJ2R|Name=Package
|RECORD=41|OwnerIndex=2046|IndexInSheet=22|OwnerPartId=-1|Location.X=484|Location.Y=762|Color=8388608|FontID=1|IsHidden=T|Text=-55°C|Name=Temperature Range Low
|RECORD=41|OwnerIndex=2046|IndexInSheet=23|OwnerPartId=-1|Location.X=484|Location.Y=762|Color=8388608|FontID=1|IsHidden=T|Text=1%|Name=Tolerance
|RECORD=41|OwnerIndex=2046|IndexInSheet=24|OwnerPartId=-1|Location.X=484|Location.Y=762|Color=8388608|FontID=1|IsHidden=T|Text=ERJ|Name=Series
|RECORD=41|OwnerIndex=2046|IndexInSheet=25|OwnerPartId=-1|Location.X=484|Location.Y=762|Color=8388608|FontID=1|IsHidden=T|Text=ERJ-2RKF1502X|Name=Manufacturer Part Number
|RECORD=41|OwnerIndex=2046|IndexInSheet=26|OwnerPartId=-1|Location.X=484|Location.Y=762|Color=8388608|FontID=3|IsHidden=T|Text=https://b2b-api.panasonic.eu/file_stream/pids/fileversion/1180|Name=Footprint Url
|RECORD=41|OwnerIndex=2046|IndexInSheet=27|OwnerPartId=-1|Location.X=484|Location.Y=762|Color=8388608|FontID=1|IsHidden=T|Text=Res Thick Film 1.0 x 0.5 mm 15K Ohm 1% 0.1W(1/10W) 100ppm/ C Molded SMD Punched Carrier T/R|Name=Mouser Description
|RECORD=41|OwnerIndex=2046|IndexInSheet=28|OwnerPartId=-1|Location.X=484|Location.Y=762|Color=8388608|FontID=1|IsHidden=T|Text=Thick Film|Name=Composition
|RECORD=41|OwnerIndex=2046|IndexInSheet=29|OwnerPartId=-1|Location.X=484|Location.Y=762|Color=8388608|FontID=1|IsHidden=T|Text=Yes|Name=Lead Free
|RECORD=41|OwnerIndex=2046|IndexInSheet=30|OwnerPartId=-1|Location.X=484|Location.Y=762|Color=8388608|FontID=1|IsHidden=T|Text=Chip SMD Resistors|Name=Device Class L3
|RECORD=41|OwnerIndex=2046|IndexInSheet=31|OwnerPartId=-1|Location.X=484|Location.Y=762|Color=8388608|FontID=1|IsHidden=T|Text=15kO|Name=Resistance
|RECORD=41|OwnerIndex=2046|IndexInSheet=32|OwnerPartId=-1|Location.X=484|Location.Y=762|Color=8388608|FontID=3|IsHidden=T|Text=https://octopart.com/erj-2rkf1502x-panasonic-55404985|Name=Octopart
|RECORD=41|OwnerIndex=2046|IndexInSheet=33|OwnerPartId=-1|Location.X=484|Location.Y=762|Color=8388608|FontID=1|IsHidden=T|Text=TRUE|Name=RoHS
|RECORD=41|OwnerIndex=2046|IndexInSheet=34|OwnerPartId=-1|Location.X=484|Location.Y=762|Color=8388608|FontID=1|IsHidden=T|Text=100ppm/°C|Name=Temperature Coefficient
|RECORD=41|OwnerIndex=2046|IndexInSheet=35|OwnerPartId=-1|Location.X=484|Location.Y=762|Color=8388608|FontID=1|IsHidden=T|Text=0.1W|Name=Power Rating
|RECORD=41|OwnerIndex=2046|IndexInSheet=36|OwnerPartId=-1|Location.X=484|Location.Y=762|Color=8388608|FontID=1|IsHidden=T|Text=Panasonic|Name=Manufacturer
|RECORD=41|OwnerIndex=2046|IndexInSheet=37|OwnerPartId=-1|Location.X=484|Location.Y=762|Color=8388608|FontID=1|IsHidden=T|Text=15kO|Name=Value
|RECORD=41|OwnerIndex=2046|IndexInSheet=38|OwnerPartId=-1|Location.X=484|Location.Y=762|Color=8388608|FontID=1|IsHidden=T|Text=+155°C|Name=Temperature Range High
|RECORD=41|OwnerIndex=2046|IndexInSheet=39|OwnerPartId=-1|Location.X=484|Location.Y=762|Color=8388608|FontID=1|IsHidden=T|Text=Datasheet|Name=ComponentLink2Description
|RECORD=34|OwnerIndex=2046|IndexInSheet=-1|OwnerPartId=-1|Location.X=480|Location.Y=700|Orientation=1|Color=8388608|FontID=2|Text=R83|Name=Designator|ReadOnlyState=1
|RECORD=41|OwnerIndex=2046|IndexInSheet=-1|OwnerPartId=1|Location.X=510|Location.Y=700|Orientation=1|Color=8388608|FontID=2|Text=15K_1%_0402|Name=Comment
|RECORD=44|OwnerIndex=2046
|RECORD=45|OwnerIndex=2091|IndexInSheet=-1|UseComponentLibrary=T|ModelName=FP-ERJ2R-MFG|ModelType=PCBLIB|DatafileCount=1|ModelDatafileEntity0=FP-ERJ2R-MFG|ModelDatafileKind0=PCBLib|IsCurrent=T|DatalinksLocked=T|DatabaseDatalinksLocked=T
|RECORD=46|OwnerIndex=2092
|RECORD=48|OwnerIndex=2092
|RECORD=45|OwnerIndex=2091|IndexInSheet=-1|UseComponentLibrary=T|ModelName=FP-ERJ2R-IPC_C|ModelType=PCBLIB|DatafileCount=1|ModelDatafileEntity0=FP-ERJ2R-IPC_C|ModelDatafileKind0=PCBLib|DatalinksLocked=T|DatabaseDatalinksLocked=T
|RECORD=46|OwnerIndex=2095
|RECORD=48|OwnerIndex=2095
|RECORD=45|OwnerIndex=2091|IndexInSheet=-1|UseComponentLibrary=T|ModelName=FP-ERJ2R-IPC_B|ModelType=PCBLIB|DatafileCount=1|ModelDatafileEntity0=FP-ERJ2R-IPC_B|ModelDatafileKind0=PCBLib|DatalinksLocked=T|DatabaseDatalinksLocked=T
|RECORD=46|OwnerIndex=2098
|RECORD=48|OwnerIndex=2098
|RECORD=45|OwnerIndex=2091|IndexInSheet=-1|UseComponentLibrary=T|ModelName=FP-ERJ2R-IPC_A|ModelType=PCBLIB|DatafileCount=1|ModelDatafileEntity0=FP-ERJ2R-IPC_A|ModelDatafileKind0=PCBLib|DatalinksLocked=T|DatabaseDatalinksLocked=T
|RECORD=46|OwnerIndex=2101
|RECORD=48|OwnerIndex=2101
|RECORD=27|IndexInSheet=277|OwnerPartId=-1|LineWidth=1|Color=8388608|LocationCount=4|X1=490|Y1=760|X2=490|Y2=770|X3=450|Y3=770|X4=450|Y4=740
|RECORD=27|IndexInSheet=278|OwnerPartId=-1|LineWidth=1|Color=8388608|LocationCount=2|X1=490|Y1=770|X2=490|Y2=790
|RECORD=1|LibReference=CAP|PartCount=2|DisplayModeCount=2|IndexInSheet=279|OwnerPartId=-1|Location.X=250|Location.Y=750|Orientation=1|CurrentPartId=1|SourceLibraryName=Altium Content Vault|TargetFileName=*|AreaColor=11599871|Color=128|PartIDLocked=F|DesignItemId=CMP-2008-04368-1|AllPinCount=2
|RECORD=2|OwnerIndex=2106|OwnerPartId=1|OwnerPartDisplayMode=1|FormalType=1|Electrical=4|PinConglomerate=35|PinLength=10|Location.X=260|Location.Y=750|Name=1|Designator=1|PinPropagationDelay=0.000000E+000
|RECORD=2|OwnerIndex=2106|OwnerPartId=1|OwnerPartDisplayMode=1|FormalType=1|Electrical=4|PinConglomerate=33|PinLength=10|Location.X=260|Location.Y=760|Name=2|Designator=2|PinPropagationDelay=0.000000E+000
|RECORD=13|OwnerIndex=2106|IsNotAccesible=T|IndexInSheet=2|OwnerPartId=1|OwnerPartDisplayMode=1|Location.X=268|Location.Y=750|Corner.X=252|Corner.Y=750|LineWidth=1|Color=16711680
|RECORD=13|OwnerIndex=2106|IsNotAccesible=T|IndexInSheet=3|OwnerPartId=1|OwnerPartDisplayMode=1|Location.X=260|Location.Y=754|Corner.X=260|Corner.Y=760|LineWidth=1|Color=16711680
|RECORD=12|OwnerIndex=2106|IsNotAccesible=T|IndexInSheet=4|OwnerPartId=1|OwnerPartDisplayMode=1|Location.X=260|Location.Y=770|Radius=16|LineWidth=1|StartAngle=241.000|EndAngle=270.000|Color=16711680
|RECORD=12|OwnerIndex=2106|IsNotAccesible=T|IndexInSheet=5|OwnerPartId=1|OwnerPartDisplayMode=1|Location.X=260|Location.Y=770|Radius=16|LineWidth=1|StartAngle=270.000|EndAngle=299.000|Color=16711680
|RECORD=2|OwnerIndex=2106|OwnerPartId=1|FormalType=1|Electrical=4|PinConglomerate=35|PinLength=10|Location.X=260|Location.Y=750|Name=1|Designator=1|PinPropagationDelay=0.000000E+000
|RECORD=2|OwnerIndex=2106|OwnerPartId=1|FormalType=1|Electrical=4|PinConglomerate=33|PinLength=10|Location.X=260|Location.Y=760|Name=2|Designator=2|PinPropagationDelay=0.000000E+000
|RECORD=13|OwnerIndex=2106|IsNotAccesible=T|IndexInSheet=8|OwnerPartId=1|Location.X=252|Location.Y=757|Corner.X=268|Corner.Y=757|LineWidth=1|Color=16711680
|RECORD=13|OwnerIndex=2106|IsNotAccesible=T|IndexInSheet=9|OwnerPartId=1|Location.X=268|Location.Y=753|Corner.X=252|Corner.Y=753|LineWidth=1|Color=16711680
|RECORD=6|OwnerIndex=2106|IsNotAccesible=T|IndexInSheet=10|OwnerPartId=1|LineWidth=1|Color=16711680|LocationCount=2|X1=260|Y1=750|X2=260|Y2=753
|RECORD=6|OwnerIndex=2106|IsNotAccesible=T|IndexInSheet=11|OwnerPartId=1|LineWidth=1|Color=16711680|LocationCount=2|X1=260|Y1=760|X2=260|Y2=757
|RECORD=41|OwnerIndex=2106|IndexInSheet=12|OwnerPartId=-1|Location.X=251|Location.Y=772|Color=8388608|FontID=1|IsHidden=T|Text=GRM1555C1H470JA01D|Name=Part Number
|RECORD=41|OwnerIndex=2106|IndexInSheet=13|OwnerPartId=-1|Location.X=251|Location.Y=772|Color=8388608|FontID=1|IsHidden=T|Text=Murata|Name=Manufacturer
|RECORD=34|OwnerIndex=2106|IndexInSheet=-1|OwnerPartId=-1|Location.X=250|Location.Y=740|Orientation=1|Color=8388608|FontID=2|Text=C87|Name=Designator|ReadOnlyState=1
|RECORD=41|OwnerIndex=2106|IndexInSheet=-1|OwnerPartId=-1|Location.X=280|Location.Y=720|Orientation=1|Color=8388608|FontID=2|Text=47pF_50V_0402|Name=Comment
|RECORD=44|OwnerIndex=2106
|RECORD=45|OwnerIndex=2127|IndexInSheet=-1|Description=Chip Capacitor, 2-Leads, Body 1.00x0.50mm, IPC High Density|UseComponentLibrary=T|ModelName=CAPC1005X55X25LL05T10|ModelType=PCBLIB|DatafileCount=1|ModelDatafileEntity0=CAPC1005X55X25LL05T10|ModelDatafileKind0=PCBLib|IsCurrent=T|DatalinksLocked=T|DatabaseDatalinksLocked=T
|RECORD=46|OwnerIndex=2128
|RECORD=48|OwnerIndex=2128
|RECORD=41|OwnerIndex=2130|IndexInSheet=-1|OwnerPartId=-1|Color=8388608|FontID=1|IsHidden=T|Text=2D|Name=Available Preview Images
|RECORD=45|OwnerIndex=2127|IndexInSheet=-1|Description=Chip Capacitor, 2-Leads, Body 1.00x0.50mm, IPC Medium Density|UseComponentLibrary=T|ModelName=CAPC1005X55X25NL05T10|ModelType=PCBLIB|DatafileCount=1|ModelDatafileEntity0=CAPC1005X55X25NL05T10|ModelDatafileKind0=PCBLib|DatalinksLocked=T|DatabaseDatalinksLocked=T
|RECORD=46|OwnerIndex=2132
|RECORD=48|OwnerIndex=2132
|RECORD=41|OwnerIndex=2134|IndexInSheet=-1|OwnerPartId=-1|Color=8388608|FontID=1|IsHidden=T|Text=2D|Name=Available Preview Images
|RECORD=45|OwnerIndex=2127|IndexInSheet=-1|Description=Chip Capacitor, 2-Leads, Body 1.00x0.50mm, IPC Low Density|UseComponentLibrary=T|ModelName=CAPC1005X55X25ML05T10|ModelType=PCBLIB|DatafileCount=1|ModelDatafileEntity0=CAPC1005X55X25ML05T10|ModelDatafileKind0=PCBLib|DatalinksLocked=T|DatabaseDatalinksLocked=T
|RECORD=46|OwnerIndex=2136
|RECORD=48|OwnerIndex=2136
|RECORD=41|OwnerIndex=2138|IndexInSheet=-1|OwnerPartId=-1|Color=8388608|FontID=1|IsHidden=T|Text=2D|Name=Available Preview Images
|RECORD=1|LibReference=CAP|PartCount=2|DisplayModeCount=2|IndexInSheet=280|OwnerPartId=-1|Location.X=290|Location.Y=750|Orientation=1|CurrentPartId=1|SourceLibraryName=Altium Content Vault|TargetFileName=*|AreaColor=11599871|Color=128|PartIDLocked=F|DesignItemId=CMP-2008-04368-1|AllPinCount=2
|RECORD=2|OwnerIndex=2140|OwnerPartId=1|OwnerPartDisplayMode=1|FormalType=1|Electrical=4|PinConglomerate=35|PinLength=10|Location.X=300|Location.Y=750|Name=1|Designator=1|PinPropagationDelay=0.000000E+000
|RECORD=2|OwnerIndex=2140|OwnerPartId=1|OwnerPartDisplayMode=1|FormalType=1|Electrical=4|PinConglomerate=33|PinLength=10|Location.X=300|Location.Y=760|Name=2|Designator=2|PinPropagationDelay=0.000000E+000
|RECORD=13|OwnerIndex=2140|IsNotAccesible=T|IndexInSheet=2|OwnerPartId=1|OwnerPartDisplayMode=1|Location.X=308|Location.Y=750|Corner.X=292|Corner.Y=750|LineWidth=1|Color=16711680
|RECORD=13|OwnerIndex=2140|IsNotAccesible=T|IndexInSheet=3|OwnerPartId=1|OwnerPartDisplayMode=1|Location.X=300|Location.Y=754|Corner.X=300|Corner.Y=760|LineWidth=1|Color=16711680
|RECORD=12|OwnerIndex=2140|IsNotAccesible=T|IndexInSheet=4|OwnerPartId=1|OwnerPartDisplayMode=1|Location.X=300|Location.Y=770|Radius=16|LineWidth=1|StartAngle=241.000|EndAngle=270.000|Color=16711680
|RECORD=12|OwnerIndex=2140|IsNotAccesible=T|IndexInSheet=5|OwnerPartId=1|OwnerPartDisplayMode=1|Location.X=300|Location.Y=770|Radius=16|LineWidth=1|StartAngle=270.000|EndAngle=299.000|Color=16711680
|RECORD=2|OwnerIndex=2140|OwnerPartId=1|FormalType=1|Electrical=4|PinConglomerate=35|PinLength=10|Location.X=300|Location.Y=750|Name=1|Designator=1|PinPropagationDelay=0.000000E+000
|RECORD=2|OwnerIndex=2140|OwnerPartId=1|FormalType=1|Electrical=4|PinConglomerate=33|PinLength=10|Location.X=300|Location.Y=760|Name=2|Designator=2|PinPropagationDelay=0.000000E+000
|RECORD=13|OwnerIndex=2140|IsNotAccesible=T|IndexInSheet=8|OwnerPartId=1|Location.X=292|Location.Y=757|Corner.X=308|Corner.Y=757|LineWidth=1|Color=16711680
|RECORD=13|OwnerIndex=2140|IsNotAccesible=T|IndexInSheet=9|OwnerPartId=1|Location.X=308|Location.Y=753|Corner.X=292|Corner.Y=753|LineWidth=1|Color=16711680
|RECORD=6|OwnerIndex=2140|IsNotAccesible=T|IndexInSheet=10|OwnerPartId=1|LineWidth=1|Color=16711680|LocationCount=2|X1=300|Y1=750|X2=300|Y2=753
|RECORD=6|OwnerIndex=2140|IsNotAccesible=T|IndexInSheet=11|OwnerPartId=1|LineWidth=1|Color=16711680|LocationCount=2|X1=300|Y1=760|X2=300|Y2=757
|RECORD=41|OwnerIndex=2140|IndexInSheet=12|OwnerPartId=-1|Location.X=291|Location.Y=772|Color=8388608|FontID=1|IsHidden=T|Text=GRM1555C1H470JA01D|Name=Part Number
|RECORD=41|OwnerIndex=2140|IndexInSheet=13|OwnerPartId=-1|Location.X=291|Location.Y=772|Color=8388608|FontID=1|IsHidden=T|Text=Murata|Name=Manufacturer
|RECORD=34|OwnerIndex=2140|IndexInSheet=-1|OwnerPartId=-1|Location.X=290|Location.Y=740|Orientation=1|Color=8388608|FontID=2|Text=C88|Name=Designator|ReadOnlyState=1
|RECORD=41|OwnerIndex=2140|IndexInSheet=-1|OwnerPartId=-1|Location.X=320|Location.Y=720|Orientation=1|Color=8388608|FontID=2|Text=47pF_50V_0402|Name=Comment
|RECORD=44|OwnerIndex=2140
|RECORD=45|OwnerIndex=2161|IndexInSheet=-1|Description=Chip Capacitor, 2-Leads, Body 1.00x0.50mm, IPC High Density|UseComponentLibrary=T|ModelName=CAPC1005X55X25LL05T10|ModelType=PCBLIB|DatafileCount=1|ModelDatafileEntity0=CAPC1005X55X25LL05T10|ModelDatafileKind0=PCBLib|IsCurrent=T|DatalinksLocked=T|DatabaseDatalinksLocked=T
|RECORD=46|OwnerIndex=2162
|RECORD=48|OwnerIndex=2162
|RECORD=41|OwnerIndex=2164|IndexInSheet=-1|OwnerPartId=-1|Color=8388608|FontID=1|IsHidden=T|Text=2D|Name=Available Preview Images
|RECORD=45|OwnerIndex=2161|IndexInSheet=-1|Description=Chip Capacitor, 2-Leads, Body 1.00x0.50mm, IPC Medium Density|UseComponentLibrary=T|ModelName=CAPC1005X55X25NL05T10|ModelType=PCBLIB|DatafileCount=1|ModelDatafileEntity0=CAPC1005X55X25NL05T10|ModelDatafileKind0=PCBLib|DatalinksLocked=T|DatabaseDatalinksLocked=T
|RECORD=46|OwnerIndex=2166
|RECORD=48|OwnerIndex=2166
|RECORD=41|OwnerIndex=2168|IndexInSheet=-1|OwnerPartId=-1|Color=8388608|FontID=1|IsHidden=T|Text=2D|Name=Available Preview Images
|RECORD=45|OwnerIndex=2161|IndexInSheet=-1|Description=Chip Capacitor, 2-Leads, Body 1.00x0.50mm, IPC Low Density|UseComponentLibrary=T|ModelName=CAPC1005X55X25ML05T10|ModelType=PCBLIB|DatafileCount=1|ModelDatafileEntity0=CAPC1005X55X25ML05T10|ModelDatafileKind0=PCBLib|DatalinksLocked=T|DatabaseDatalinksLocked=T
|RECORD=46|OwnerIndex=2170
|RECORD=48|OwnerIndex=2170
|RECORD=41|OwnerIndex=2172|IndexInSheet=-1|OwnerPartId=-1|Color=8388608|FontID=1|IsHidden=T|Text=2D|Name=Available Preview Images
|RECORD=29|IndexInSheet=-1|OwnerPartId=-1|Location.X=110|Location.Y=450|Color=128
|RECORD=29|IndexInSheet=-1|OwnerPartId=-1|Location.X=180|Location.Y=680|Color=128
|RECORD=29|IndexInSheet=-1|OwnerPartId=-1|Location.X=180|Location.Y=700|Color=128
|RECORD=29|IndexInSheet=-1|OwnerPartId=-1|Location.X=180|Location.Y=720|Color=128
|RECORD=29|IndexInSheet=-1|OwnerPartId=-1|Location.X=180|Location.Y=740|Color=128
|RECORD=29|IndexInSheet=-1|OwnerPartId=-1|Location.X=220|Location.Y=720|Color=128
|RECORD=29|IndexInSheet=-1|OwnerPartId=-1|Location.X=230|Location.Y=470|Color=128
|RECORD=29|IndexInSheet=-1|OwnerPartId=-1|Location.X=240|Location.Y=850|Color=128
|RECORD=29|IndexInSheet=-1|OwnerPartId=-1|Location.X=260|Location.Y=720|Color=128
|RECORD=29|IndexInSheet=-1|OwnerPartId=-1|Location.X=260|Location.Y=810|Color=128
|RECORD=29|IndexInSheet=-1|OwnerPartId=-1|Location.X=270|Location.Y=450|Color=128
|RECORD=29|IndexInSheet=-1|OwnerPartId=-1|Location.X=300|Location.Y=720|Color=128
|RECORD=29|IndexInSheet=-1|OwnerPartId=-1|Location.X=300|Location.Y=830|Color=128
|RECORD=29|IndexInSheet=-1|OwnerPartId=-1|Location.X=340|Location.Y=720|Color=128
|RECORD=29|IndexInSheet=-1|OwnerPartId=-1|Location.X=340|Location.Y=850|Color=128
|RECORD=29|IndexInSheet=-1|OwnerPartId=-1|Location.X=380|Location.Y=850|Color=128
|RECORD=29|IndexInSheet=-1|OwnerPartId=-1|Location.X=400|Location.Y=850|Color=128
|RECORD=29|IndexInSheet=-1|OwnerPartId=-1|Location.X=420|Location.Y=290|Color=128
|RECORD=29|IndexInSheet=-1|OwnerPartId=-1|Location.X=460|Location.Y=80|Color=128
|RECORD=29|IndexInSheet=-1|OwnerPartId=-1|Location.X=460|Location.Y=130|Color=128
|RECORD=29|IndexInSheet=-1|OwnerPartId=-1|Location.X=490|Location.Y=690|Color=128
|RECORD=29|IndexInSheet=-1|OwnerPartId=-1|Location.X=490|Location.Y=770|Color=128
|RECORD=29|IndexInSheet=-1|OwnerPartId=-1|Location.X=490|Location.Y=790|Color=128
|RECORD=29|IndexInSheet=-1|OwnerPartId=-1|Location.X=550|Location.Y=680|Color=128
|RECORD=29|IndexInSheet=-1|OwnerPartId=-1|Location.X=550|Location.Y=750|Color=128
|RECORD=29|IndexInSheet=-1|OwnerPartId=-1|Location.X=550|Location.Y=770|Color=128
|RECORD=29|IndexInSheet=-1|OwnerPartId=-1|Location.X=620|Location.Y=560|Color=128
|RECORD=29|IndexInSheet=-1|OwnerPartId=-1|Location.X=630|Location.Y=210|Color=128
|RECORD=29|IndexInSheet=-1|OwnerPartId=-1|Location.X=630|Location.Y=270|Color=128
|RECORD=29|IndexInSheet=-1|OwnerPartId=-1|Location.X=660|Location.Y=170|Color=128
|RECORD=29|IndexInSheet=-1|OwnerPartId=-1|Location.X=660|Location.Y=250|Color=128
|RECORD=29|IndexInSheet=-1|OwnerPartId=-1|Location.X=660|Location.Y=350|Color=128
|RECORD=29|IndexInSheet=-1|OwnerPartId=-1|Location.X=660|Location.Y=400|Color=128
|RECORD=29|IndexInSheet=-1|OwnerPartId=-1|Location.X=750|Location.Y=770|Color=128
|RECORD=29|IndexInSheet=-1|OwnerPartId=-1|Location.X=840|Location.Y=480|Color=128
|RECORD=29|IndexInSheet=-1|OwnerPartId=-1|Location.X=860|Location.Y=440|Color=128
|RECORD=29|IndexInSheet=-1|OwnerPartId=-1|Location.X=1140|Location.Y=680|Color=128
|RECORD=29|IndexInSheet=-1|OwnerPartId=-1|Location.X=1180|Location.Y=470|Color=128
|RECORD=29|IndexInSheet=-1|OwnerPartId=-1|Location.X=1180|Location.Y=520|Color=128
|RECORD=29|IndexInSheet=-1|OwnerPartId=-1|Location.X=1360|Location.Y=600|Color=128
|RECORD=29|IndexInSheet=-1|OwnerPartId=-1|Location.X=1370|Location.Y=560|Color=128